(kicad_sch
	(version 20250114)
	(generator "eeschema")
	(generator_version "9.0")
	(paper "A3")
	(title_block
		(title "Antmicro Baseboard for Jetson AGX Thor")
		(date "2026-02-17")
		(rev "1.1.0")
		(company "Antmicro Ltd")
		(comment 1 "www.antmicro.com")
	)
	(bus_alias "GPIO"
		(members "USER_LED0" "USER_LED1" "USER_BTN0" "USER_BTN1" "04" "05" "08"
			"09" "10" "11" "12" "13" "14" "15" "16" "17" "18" "19" "20" "21" "24"
			"MCLK02" "MCLK03" "MCLK04" "MCLK05" "MCLK01" "27" "32" "34" "36" "64"
			"65" "67"
		)
	)
	(text "User Buttons"
		(exclude_from_sim no)
		(at 207.264 181.864 0)
		(effects
			(font
				(size 2.54 2.54)
				(thickness 0.3175)
			)
		)
	)
	(text "I2C Addr: 0x2E"
		(exclude_from_sim no)
		(at 90.678 97.028 0)
		(effects
			(font
				(size 1.27 1.27)
			)
			(justify left bottom)
		)
	)
	(text "Fan connector"
		(exclude_from_sim no)
		(at 70.612 113.284 0)
		(effects
			(font
				(size 2.54 2.54)
				(thickness 0.3175)
			)
		)
	)
	(text "I2C addr: 0x20"
		(exclude_from_sim no)
		(at 312.42 157.48 0)
		(effects
			(font
				(size 1.27 1.27)
			)
		)
	)
	(text "ID EEPROM"
		(exclude_from_sim no)
		(at 204.978 116.078 0)
		(effects
			(font
				(size 2.54 2.54)
				(thickness 0.3175)
			)
		)
	)
	(text "I^{2}C connectors"
		(exclude_from_sim no)
		(at 215.9 22.352 0)
		(effects
			(font
				(size 2.54 2.54)
				(thickness 0.3175)
			)
		)
	)
	(text "GPIO Expander"
		(exclude_from_sim no)
		(at 326.898 111.76 0)
		(effects
			(font
				(size 2.54 2.54)
				(thickness 0.3175)
			)
		)
	)
	(text "Note: Max current set to 0.75A"
		(exclude_from_sim no)
		(at 310.388 38.1 0)
		(effects
			(font
				(size 1.27 1.27)
			)
		)
	)
	(text "TPM\n"
		(exclude_from_sim no)
		(at 73.914 18.542 0)
		(effects
			(font
				(size 2.54 2.54)
				(thickness 0.3175)
			)
		)
	)
	(text "I2C addres (7-bit): \n- EEPROM: 0x50\n- UUID: 0x58"
		(exclude_from_sim no)
		(at 198.374 164.084 0)
		(effects
			(font
				(size 1.27 1.27)
			)
			(justify left)
		)
	)
	(text "User LEDs"
		(exclude_from_sim no)
		(at 70.358 181.102 0)
		(effects
			(font
				(size 2.54 2.54)
				(thickness 0.3175)
			)
		)
	)
	(junction
		(at 300.99 129.54)
		(diameter 0)
		(color 0 0 0 0)
	)
	(junction
		(at 102.87 148.59)
		(diameter 0)
		(color 0 0 0 0)
	)
	(junction
		(at 316.23 49.53)
		(diameter 0)
		(color 0 0 0 0)
	)
	(junction
		(at 45.72 139.7)
		(diameter 0)
		(color 0 0 0 0)
	)
	(junction
		(at 48.26 30.48)
		(diameter 0)
		(color 0 0 0 0)
	)
	(junction
		(at 88.9 127)
		(diameter 0)
		(color 0 0 0 0)
	)
	(junction
		(at 219.71 87.63)
		(diameter 0)
		(color 0 0 0 0)
	)
	(junction
		(at 57.15 66.04)
		(diameter 0)
		(color 0 0 0 0)
	)
	(junction
		(at 210.82 220.98)
		(diameter 0)
		(color 0 0 0 0)
	)
	(junction
		(at 227.33 49.53)
		(diameter 0)
		(color 0 0 0 0)
	)
	(junction
		(at 318.77 82.55)
		(diameter 0)
		(color 0 0 0 0)
	)
	(junction
		(at 67.31 30.48)
		(diameter 0)
		(color 0 0 0 0)
	)
	(junction
		(at 326.39 77.47)
		(diameter 0)
		(color 0 0 0 0)
	)
	(junction
		(at 107.95 144.78)
		(diameter 0)
		(color 0 0 0 0)
	)
	(junction
		(at 35.56 144.78)
		(diameter 0)
		(color 0 0 0 0)
	)
	(junction
		(at 237.49 49.53)
		(diameter 0)
		(color 0 0 0 0)
	)
	(junction
		(at 204.47 208.28)
		(diameter 0)
		(color 0 0 0 0)
	)
	(junction
		(at 264.16 38.1)
		(diameter 0)
		(color 0 0 0 0)
	)
	(junction
		(at 204.47 237.49)
		(diameter 0)
		(color 0 0 0 0)
	)
	(junction
		(at 208.28 237.49)
		(diameter 0)
		(color 0 0 0 0)
	)
	(junction
		(at 227.33 80.01)
		(diameter 0)
		(color 0 0 0 0)
	)
	(junction
		(at 44.45 223.52)
		(diameter 0)
		(color 0 0 0 0)
	)
	(junction
		(at 278.13 135.89)
		(diameter 0)
		(color 0 0 0 0)
	)
	(junction
		(at 274.32 54.61)
		(diameter 0)
		(color 0 0 0 0)
	)
	(junction
		(at 30.48 142.24)
		(diameter 0)
		(color 0 0 0 0)
	)
	(junction
		(at 274.32 38.1)
		(diameter 0)
		(color 0 0 0 0)
	)
	(junction
		(at 191.77 142.24)
		(diameter 0)
		(color 0 0 0 0)
	)
	(junction
		(at 218.44 153.67)
		(diameter 0)
		(color 0 0 0 0)
	)
	(junction
		(at 86.36 88.9)
		(diameter 0)
		(color 0 0 0 0)
	)
	(junction
		(at 76.2 30.48)
		(diameter 0)
		(color 0 0 0 0)
	)
	(junction
		(at 83.82 50.8)
		(diameter 0)
		(color 0 0 0 0)
	)
	(junction
		(at 290.83 123.19)
		(diameter 0)
		(color 0 0 0 0)
	)
	(junction
		(at 208.28 208.28)
		(diameter 0)
		(color 0 0 0 0)
	)
	(junction
		(at 328.93 85.09)
		(diameter 0)
		(color 0 0 0 0)
	)
	(junction
		(at 308.61 87.63)
		(diameter 0)
		(color 0 0 0 0)
	)
	(junction
		(at 185.42 38.1)
		(diameter 0)
		(color 0 0 0 0)
	)
	(junction
		(at 116.84 149.86)
		(diameter 0)
		(color 0 0 0 0)
	)
	(junction
		(at 194.31 144.78)
		(diameter 0)
		(color 0 0 0 0)
	)
	(junction
		(at 279.4 54.61)
		(diameter 0)
		(color 0 0 0 0)
	)
	(junction
		(at 100.33 148.59)
		(diameter 0)
		(color 0 0 0 0)
	)
	(junction
		(at 190.5 54.61)
		(diameter 0)
		(color 0 0 0 0)
	)
	(junction
		(at 240.03 85.09)
		(diameter 0)
		(color 0 0 0 0)
	)
	(junction
		(at 210.82 250.19)
		(diameter 0)
		(color 0 0 0 0)
	)
	(junction
		(at 86.36 91.44)
		(diameter 0)
		(color 0 0 0 0)
	)
	(junction
		(at 73.66 125.73)
		(diameter 0)
		(color 0 0 0 0)
	)
	(junction
		(at 116.84 139.7)
		(diameter 0)
		(color 0 0 0 0)
	)
	(junction
		(at 105.41 142.24)
		(diameter 0)
		(color 0 0 0 0)
	)
	(junction
		(at 210.82 208.28)
		(diameter 0)
		(color 0 0 0 0)
	)
	(junction
		(at 237.49 77.47)
		(diameter 0)
		(color 0 0 0 0)
	)
	(junction
		(at 196.85 151.13)
		(diameter 0)
		(color 0 0 0 0)
	)
	(junction
		(at 208.28 250.19)
		(diameter 0)
		(color 0 0 0 0)
	)
	(junction
		(at 40.64 125.73)
		(diameter 0)
		(color 0 0 0 0)
	)
	(junction
		(at 114.3 127)
		(diameter 0)
		(color 0 0 0 0)
	)
	(junction
		(at 196.85 153.67)
		(diameter 0)
		(color 0 0 0 0)
	)
	(junction
		(at 93.98 223.52)
		(diameter 0)
		(color 0 0 0 0)
	)
	(junction
		(at 210.82 237.49)
		(diameter 0)
		(color 0 0 0 0)
	)
	(junction
		(at 95.25 124.46)
		(diameter 0)
		(color 0 0 0 0)
	)
	(junction
		(at 316.23 80.01)
		(diameter 0)
		(color 0 0 0 0)
	)
	(junction
		(at 185.42 54.61)
		(diameter 0)
		(color 0 0 0 0)
	)
	(junction
		(at 175.26 38.1)
		(diameter 0)
		(color 0 0 0 0)
	)
	(junction
		(at 326.39 49.53)
		(diameter 0)
		(color 0 0 0 0)
	)
	(junction
		(at 58.42 30.48)
		(diameter 0)
		(color 0 0 0 0)
	)
	(junction
		(at 208.28 220.98)
		(diameter 0)
		(color 0 0 0 0)
	)
	(junction
		(at 83.82 53.34)
		(diameter 0)
		(color 0 0 0 0)
	)
	(junction
		(at 78.74 77.47)
		(diameter 0)
		(color 0 0 0 0)
	)
	(junction
		(at 229.87 82.55)
		(diameter 0)
		(color 0 0 0 0)
	)
	(no_connect
		(at 87.63 76.2)
	)
	(no_connect
		(at 195.58 52.07)
	)
	(no_connect
		(at 87.63 81.28)
	)
	(no_connect
		(at 284.48 52.07)
	)
	(no_connect
		(at 322.58 149.86)
	)
	(no_connect
		(at 87.63 78.74)
	)
	(bus_entry
		(at 69.85 248.92)
		(size 1.27 1.27)
		(stroke
			(width 0)
			(type default)
		)
	)
	(bus_entry
		(at 377.19 135.89)
		(size -1.27 1.27)
		(stroke
			(width 0)
			(type default)
		)
	)
	(bus_entry
		(at 200.66 78.74)
		(size 1.27 1.27)
		(stroke
			(width 0)
			(type default)
		)
	)
	(bus_entry
		(at 285.75 140.97)
		(size 1.27 1.27)
		(stroke
			(width 0)
			(type default)
		)
	)
	(bus_entry
		(at 295.91 81.28)
		(size 1.27 1.27)
		(stroke
			(width 0)
			(type default)
		)
	)
	(bus_entry
		(at 69.85 246.38)
		(size 1.27 1.27)
		(stroke
			(width 0)
			(type default)
		)
	)
	(bus_entry
		(at 377.19 133.35)
		(size -1.27 1.27)
		(stroke
			(width 0)
			(type default)
		)
	)
	(bus_entry
		(at 73.66 62.23)
		(size 1.27 1.27)
		(stroke
			(width 0)
			(type default)
		)
	)
	(bus_entry
		(at 176.53 140.97)
		(size 1.27 1.27)
		(stroke
			(width 0)
			(type default)
		)
	)
	(bus_entry
		(at 69.85 254)
		(size 1.27 1.27)
		(stroke
			(width 0)
			(type default)
		)
	)
	(bus_entry
		(at 200.66 81.28)
		(size 1.27 1.27)
		(stroke
			(width 0)
			(type default)
		)
	)
	(bus_entry
		(at 73.66 59.69)
		(size 1.27 1.27)
		(stroke
			(width 0)
			(type default)
		)
	)
	(bus_entry
		(at 377.19 128.27)
		(size -1.27 1.27)
		(stroke
			(width 0)
			(type default)
		)
	)
	(bus_entry
		(at 295.91 78.74)
		(size 1.27 1.27)
		(stroke
			(width 0)
			(type default)
		)
	)
	(bus_entry
		(at 176.53 143.51)
		(size 1.27 1.27)
		(stroke
			(width 0)
			(type default)
		)
	)
	(bus_entry
		(at 285.75 138.43)
		(size 1.27 1.27)
		(stroke
			(width 0)
			(type default)
		)
	)
	(bus_entry
		(at 69.85 251.46)
		(size 1.27 1.27)
		(stroke
			(width 0)
			(type default)
		)
	)
	(bus_entry
		(at 377.19 130.81)
		(size -1.27 1.27)
		(stroke
			(width 0)
			(type default)
		)
	)
	(wire
		(pts
			(xy 208.28 208.28) (xy 210.82 208.28)
		)
		(stroke
			(width 0)
			(type default)
		)
	)
	(wire
		(pts
			(xy 57.15 66.04) (xy 57.15 67.31)
		)
		(stroke
			(width 0)
			(type default)
		)
	)
	(bus
		(pts
			(xy 69.85 248.92) (xy 69.85 251.46)
		)
		(stroke
			(width 0)
			(type default)
		)
	)
	(wire
		(pts
			(xy 198.12 148.59) (xy 196.85 148.59)
		)
		(stroke
			(width 0)
			(type default)
		)
	)
	(bus
		(pts
			(xy 292.1 77.47) (xy 294.64 77.47)
		)
		(stroke
			(width 0)
			(type default)
		)
	)
	(wire
		(pts
			(xy 118.11 137.16) (xy 116.84 137.16)
		)
		(stroke
			(width 0)
			(type default)
		)
	)
	(bus
		(pts
			(xy 199.39 77.47) (xy 200.66 78.74)
		)
		(stroke
			(width 0)
			(type default)
		)
	)
	(polyline
		(pts
			(xy 353.695 128.905) (xy 353.695 127.635)
		)
		(stroke
			(width 0)
			(type default)
		)
	)
	(polyline
		(pts
			(xy 353.06 140.97) (xy 353.695 141.605)
		)
		(stroke
			(width 0)
			(type default)
		)
	)
	(wire
		(pts
			(xy 306.07 59.69) (xy 306.07 58.42)
		)
		(stroke
			(width 0)
			(type default)
		)
	)
	(wire
		(pts
			(xy 217.17 52.07) (xy 217.17 53.34)
		)
		(stroke
			(width 0)
			(type default)
		)
	)
	(bus
		(pts
			(xy 377.19 133.35) (xy 377.19 135.89)
		)
		(stroke
			(width 0)
			(type default)
		)
	)
	(polyline
		(pts
			(xy 353.695 128.27) (xy 353.06 128.27)
		)
		(stroke
			(width 0)
			(type default)
		)
	)
	(bus
		(pts
			(xy 378.46 125.73) (xy 377.19 127)
		)
		(stroke
			(width 0)
			(type default)
		)
	)
	(wire
		(pts
			(xy 278.13 129.54) (xy 278.13 135.89)
		)
		(stroke
			(width 0)
			(type default)
		)
	)
	(wire
		(pts
			(xy 194.31 138.43) (xy 194.31 144.78)
		)
		(stroke
			(width 0)
			(type default)
		)
	)
	(wire
		(pts
			(xy 83.82 53.34) (xy 83.82 50.8)
		)
		(stroke
			(width 0)
			(type default)
		)
	)
	(bus
		(pts
			(xy 377.19 130.81) (xy 377.19 133.35)
		)
		(stroke
			(width 0)
			(type default)
		)
	)
	(wire
		(pts
			(xy 300.99 149.86) (xy 302.26 149.86)
		)
		(stroke
			(width 0)
			(type default)
		)
	)
	(wire
		(pts
			(xy 67.31 30.48) (xy 67.31 31.75)
		)
		(stroke
			(width 0)
			(type default)
		)
	)
	(wire
		(pts
			(xy 290.83 121.92) (xy 290.83 123.19)
		)
		(stroke
			(width 0)
			(type default)
		)
	)
	(wire
		(pts
			(xy 44.45 223.52) (xy 46.99 223.52)
		)
		(stroke
			(width 0)
			(type default)
		)
	)
	(wire
		(pts
			(xy 213.36 147.32) (xy 218.44 147.32)
		)
		(stroke
			(width 0)
			(type default)
		)
	)
	(wire
		(pts
			(xy 303.53 87.63) (xy 308.61 87.63)
		)
		(stroke
			(width 0)
			(type default)
		)
	)
	(wire
		(pts
			(xy 210.82 237.49) (xy 231.14 237.49)
		)
		(stroke
			(width 0)
			(type default)
		)
	)
	(wire
		(pts
			(xy 204.47 250.19) (xy 208.28 250.19)
		)
		(stroke
			(width 0)
			(type default)
		)
	)
	(wire
		(pts
			(xy 283.21 38.1) (xy 274.32 38.1)
		)
		(stroke
			(width 0)
			(type default)
		)
	)
	(wire
		(pts
			(xy 227.33 80.01) (xy 227.33 88.9)
		)
		(stroke
			(width 0)
			(type default)
		)
	)
	(polyline
		(pts
			(xy 353.695 133.35) (xy 354.33 133.35)
		)
		(stroke
			(width 0)
			(type default)
		)
	)
	(polyline
		(pts
			(xy 353.06 133.35) (xy 353.695 133.985)
		)
		(stroke
			(width 0)
			(type default)
		)
	)
	(wire
		(pts
			(xy 67.31 38.1) (xy 67.31 36.83)
		)
		(stroke
			(width 0)
			(type default)
		)
	)
	(wire
		(pts
			(xy 87.63 55.88) (xy 83.82 55.88)
		)
		(stroke
			(width 0)
			(type default)
		)
	)
	(wire
		(pts
			(xy 102.87 214.63) (xy 102.87 215.9)
		)
		(stroke
			(width 0)
			(type default)
		)
	)
	(wire
		(pts
			(xy 283.21 49.53) (xy 284.48 49.53)
		)
		(stroke
			(width 0)
			(type default)
		)
	)
	(wire
		(pts
			(xy 102.87 208.28) (xy 102.87 209.55)
		)
		(stroke
			(width 0)
			(type default)
		)
	)
	(wire
		(pts
			(xy 116.84 139.7) (xy 118.11 139.7)
		)
		(stroke
			(width 0)
			(type default)
		)
	)
	(wire
		(pts
			(xy 191.77 142.24) (xy 198.12 142.24)
		)
		(stroke
			(width 0)
			(type default)
		)
	)
	(wire
		(pts
			(xy 71.12 250.19) (xy 88.9 250.19)
		)
		(stroke
			(width 0)
			(type default)
		)
	)
	(wire
		(pts
			(xy 218.44 142.24) (xy 213.36 142.24)
		)
		(stroke
			(width 0)
			(type default)
		)
	)
	(wire
		(pts
			(xy 196.85 153.67) (xy 196.85 154.94)
		)
		(stroke
			(width 0)
			(type default)
		)
	)
	(wire
		(pts
			(xy 114.3 124.46) (xy 114.3 127)
		)
		(stroke
			(width 0)
			(type default)
		)
	)
	(wire
		(pts
			(xy 88.9 127) (xy 88.9 129.54)
		)
		(stroke
			(width 0)
			(type default)
		)
	)
	(wire
		(pts
			(xy 287.02 139.7) (xy 302.26 139.7)
		)
		(stroke
			(width 0)
			(type default)
		)
	)
	(wire
		(pts
			(xy 300.99 156.21) (xy 300.99 157.48)
		)
		(stroke
			(width 0)
			(type default)
		)
	)
	(wire
		(pts
			(xy 328.93 74.93) (xy 328.93 85.09)
		)
		(stroke
			(width 0)
			(type default)
		)
	)
	(wire
		(pts
			(xy 67.31 144.78) (xy 107.95 144.78)
		)
		(stroke
			(width 0)
			(type default)
		)
	)
	(polyline
		(pts
			(xy 353.695 144.145) (xy 353.695 142.875)
		)
		(stroke
			(width 0)
			(type default)
		)
	)
	(wire
		(pts
			(xy 214.63 87.63) (xy 219.71 87.63)
		)
		(stroke
			(width 0)
			(type default)
		)
	)
	(wire
		(pts
			(xy 194.31 144.78) (xy 198.12 144.78)
		)
		(stroke
			(width 0)
			(type default)
		)
	)
	(wire
		(pts
			(xy 191.77 138.43) (xy 191.77 142.24)
		)
		(stroke
			(width 0)
			(type default)
		)
	)
	(wire
		(pts
			(xy 300.99 132.08) (xy 300.99 129.54)
		)
		(stroke
			(width 0)
			(type default)
		)
	)
	(wire
		(pts
			(xy 45.72 147.32) (xy 45.72 139.7)
		)
		(stroke
			(width 0)
			(type default)
		)
	)
	(wire
		(pts
			(xy 347.98 142.24) (xy 364.49 142.24)
		)
		(stroke
			(width 0)
			(type default)
		)
	)
	(wire
		(pts
			(xy 48.26 36.83) (xy 48.26 38.1)
		)
		(stroke
			(width 0)
			(type default)
		)
	)
	(wire
		(pts
			(xy 68.58 147.32) (xy 67.31 147.32)
		)
		(stroke
			(width 0)
			(type default)
		)
	)
	(wire
		(pts
			(xy 100.33 148.59) (xy 100.33 149.86)
		)
		(stroke
			(width 0)
			(type default)
		)
	)
	(wire
		(pts
			(xy 40.64 124.46) (xy 40.64 125.73)
		)
		(stroke
			(width 0)
			(type default)
		)
	)
	(wire
		(pts
			(xy 67.31 142.24) (xy 105.41 142.24)
		)
		(stroke
			(width 0)
			(type default)
		)
	)
	(wire
		(pts
			(xy 208.28 250.19) (xy 210.82 250.19)
		)
		(stroke
			(width 0)
			(type default)
		)
	)
	(wire
		(pts
			(xy 83.82 55.88) (xy 83.82 53.34)
		)
		(stroke
			(width 0)
			(type default)
		)
	)
	(wire
		(pts
			(xy 95.25 134.62) (xy 95.25 135.89)
		)
		(stroke
			(width 0)
			(type default)
		)
	)
	(bus
		(pts
			(xy 172.72 139.7) (xy 175.26 139.7)
		)
		(stroke
			(width 0)
			(type default)
		)
	)
	(wire
		(pts
			(xy 224.79 88.9) (xy 224.79 77.47)
		)
		(stroke
			(width 0)
			(type default)
		)
	)
	(wire
		(pts
			(xy 264.16 44.45) (xy 264.16 45.72)
		)
		(stroke
			(width 0)
			(type default)
		)
	)
	(wire
		(pts
			(xy 347.98 134.62) (xy 375.92 134.62)
		)
		(stroke
			(width 0)
			(type default)
		)
	)
	(bus
		(pts
			(xy 73.66 59.69) (xy 73.66 62.23)
		)
		(stroke
			(width 0)
			(type default)
		)
	)
	(wire
		(pts
			(xy 116.84 139.7) (xy 116.84 149.86)
		)
		(stroke
			(width 0)
			(type default)
		)
	)
	(wire
		(pts
			(xy 322.58 144.78) (xy 342.9 144.78)
		)
		(stroke
			(width 0)
			(type default)
		)
	)
	(wire
		(pts
			(xy 46.99 147.32) (xy 45.72 147.32)
		)
		(stroke
			(width 0)
			(type default)
		)
	)
	(wire
		(pts
			(xy 44.45 224.79) (xy 44.45 223.52)
		)
		(stroke
			(width 0)
			(type default)
		)
	)
	(wire
		(pts
			(xy 196.85 148.59) (xy 196.85 151.13)
		)
		(stroke
			(width 0)
			(type default)
		)
	)
	(wire
		(pts
			(xy 53.34 226.06) (xy 53.34 231.14)
		)
		(stroke
			(width 0)
			(type default)
		)
	)
	(wire
		(pts
			(xy 204.47 236.22) (xy 204.47 237.49)
		)
		(stroke
			(width 0)
			(type default)
		)
	)
	(wire
		(pts
			(xy 83.82 30.48) (xy 83.82 50.8)
		)
		(stroke
			(width 0)
			(type default)
		)
	)
	(wire
		(pts
			(xy 71.12 252.73) (xy 88.9 252.73)
		)
		(stroke
			(width 0)
			(type default)
		)
	)
	(wire
		(pts
			(xy 76.2 38.1) (xy 76.2 36.83)
		)
		(stroke
			(width 0)
			(type default)
		)
	)
	(wire
		(pts
			(xy 44.45 220.98) (xy 44.45 223.52)
		)
		(stroke
			(width 0)
			(type default)
		)
	)
	(wire
		(pts
			(xy 308.61 87.63) (xy 311.15 87.63)
		)
		(stroke
			(width 0)
			(type default)
		)
	)
	(wire
		(pts
			(xy 214.63 87.63) (xy 214.63 90.17)
		)
		(stroke
			(width 0)
			(type default)
		)
	)
	(wire
		(pts
			(xy 328.93 86.36) (xy 328.93 85.09)
		)
		(stroke
			(width 0)
			(type default)
		)
	)
	(wire
		(pts
			(xy 240.03 74.93) (xy 240.03 85.09)
		)
		(stroke
			(width 0)
			(type default)
		)
	)
	(wire
		(pts
			(xy 300.99 54.61) (xy 300.99 59.69)
		)
		(stroke
			(width 0)
			(type default)
		)
	)
	(wire
		(pts
			(xy 58.42 30.48) (xy 67.31 30.48)
		)
		(stroke
			(width 0)
			(type default)
		)
	)
	(wire
		(pts
			(xy 210.82 52.07) (xy 217.17 52.07)
		)
		(stroke
			(width 0)
			(type default)
		)
	)
	(wire
		(pts
			(xy 77.47 220.98) (xy 93.98 220.98)
		)
		(stroke
			(width 0)
			(type default)
		)
	)
	(wire
		(pts
			(xy 116.84 137.16) (xy 116.84 139.7)
		)
		(stroke
			(width 0)
			(type default)
		)
	)
	(wire
		(pts
			(xy 237.49 49.53) (xy 237.49 77.47)
		)
		(stroke
			(width 0)
			(type default)
		)
	)
	(wire
		(pts
			(xy 73.66 124.46) (xy 73.66 125.73)
		)
		(stroke
			(width 0)
			(type default)
		)
	)
	(wire
		(pts
			(xy 40.64 74.93) (xy 50.8 74.93)
		)
		(stroke
			(width 0)
			(type default)
		)
	)
	(wire
		(pts
			(xy 264.16 36.83) (xy 264.16 38.1)
		)
		(stroke
			(width 0)
			(type default)
		)
	)
	(wire
		(pts
			(xy 303.53 87.63) (xy 303.53 90.17)
		)
		(stroke
			(width 0)
			(type default)
		)
	)
	(wire
		(pts
			(xy 95.25 148.59) (xy 100.33 148.59)
		)
		(stroke
			(width 0)
			(type default)
		)
	)
	(wire
		(pts
			(xy 274.32 38.1) (xy 274.32 39.37)
		)
		(stroke
			(width 0)
			(type default)
		)
	)
	(wire
		(pts
			(xy 85.09 71.12) (xy 87.63 71.12)
		)
		(stroke
			(width 0)
			(type default)
		)
	)
	(wire
		(pts
			(xy 110.49 148.59) (xy 102.87 148.59)
		)
		(stroke
			(width 0)
			(type default)
		)
	)
	(wire
		(pts
			(xy 318.77 88.9) (xy 318.77 82.55)
		)
		(stroke
			(width 0)
			(type default)
		)
	)
	(polyline
		(pts
			(xy 353.695 138.43) (xy 353.06 138.43)
		)
		(stroke
			(width 0)
			(type default)
		)
	)
	(wire
		(pts
			(xy 105.41 142.24) (xy 118.11 142.24)
		)
		(stroke
			(width 0)
			(type default)
		)
	)
	(wire
		(pts
			(xy 208.28 237.49) (xy 208.28 238.76)
		)
		(stroke
			(width 0)
			(type default)
		)
	)
	(polyline
		(pts
			(xy 353.695 139.065) (xy 353.695 137.795)
		)
		(stroke
			(width 0)
			(type default)
		)
	)
	(wire
		(pts
			(xy 67.31 139.7) (xy 68.58 139.7)
		)
		(stroke
			(width 0)
			(type default)
		)
	)
	(wire
		(pts
			(xy 30.48 140.97) (xy 30.48 142.24)
		)
		(stroke
			(width 0)
			(type default)
		)
	)
	(polyline
		(pts
			(xy 249.555 106.045) (xy 249.555 172.72)
		)
		(stroke
			(width 0)
			(type default)
		)
	)
	(wire
		(pts
			(xy 347.98 144.78) (xy 370.84 144.78)
		)
		(stroke
			(width 0)
			(type default)
		)
	)
	(wire
		(pts
			(xy 328.93 74.93) (xy 330.2 74.93)
		)
		(stroke
			(width 0)
			(type default)
		)
	)
	(wire
		(pts
			(xy 279.4 54.61) (xy 284.48 54.61)
		)
		(stroke
			(width 0)
			(type default)
		)
	)
	(wire
		(pts
			(xy 27.94 220.98) (xy 44.45 220.98)
		)
		(stroke
			(width 0)
			(type default)
		)
	)
	(wire
		(pts
			(xy 208.28 219.71) (xy 208.28 220.98)
		)
		(stroke
			(width 0)
			(type default)
		)
	)
	(wire
		(pts
			(xy 224.79 77.47) (xy 237.49 77.47)
		)
		(stroke
			(width 0)
			(type default)
		)
	)
	(wire
		(pts
			(xy 68.58 125.73) (xy 73.66 125.73)
		)
		(stroke
			(width 0)
			(type default)
		)
	)
	(bus
		(pts
			(xy 377.19 128.27) (xy 377.19 130.81)
		)
		(stroke
			(width 0)
			(type default)
		)
	)
	(wire
		(pts
			(xy 267.97 135.89) (xy 278.13 135.89)
		)
		(stroke
			(width 0)
			(type default)
		)
	)
	(wire
		(pts
			(xy 53.34 201.93) (xy 53.34 203.2)
		)
		(stroke
			(width 0)
			(type default)
		)
	)
	(wire
		(pts
			(xy 35.56 140.97) (xy 35.56 144.78)
		)
		(stroke
			(width 0)
			(type default)
		)
	)
	(wire
		(pts
			(xy 175.26 38.1) (xy 175.26 39.37)
		)
		(stroke
			(width 0)
			(type default)
		)
	)
	(wire
		(pts
			(xy 95.25 124.46) (xy 96.52 124.46)
		)
		(stroke
			(width 0)
			(type default)
		)
	)
	(wire
		(pts
			(xy 322.58 129.54) (xy 342.9 129.54)
		)
		(stroke
			(width 0)
			(type default)
		)
	)
	(wire
		(pts
			(xy 57.15 78.74) (xy 57.15 77.47)
		)
		(stroke
			(width 0)
			(type default)
		)
	)
	(bus
		(pts
			(xy 66.04 245.11) (xy 68.58 245.11)
		)
		(stroke
			(width 0)
			(type default)
		)
	)
	(polyline
		(pts
			(xy 354.33 143.51) (xy 353.695 142.875)
		)
		(stroke
			(width 0)
			(type default)
		)
	)
	(wire
		(pts
			(xy 290.83 123.19) (xy 300.99 123.19)
		)
		(stroke
			(width 0)
			(type default)
		)
	)
	(wire
		(pts
			(xy 101.6 127) (xy 114.3 127)
		)
		(stroke
			(width 0)
			(type default)
		)
	)
	(wire
		(pts
			(xy 27.94 144.78) (xy 35.56 144.78)
		)
		(stroke
			(width 0)
			(type default)
		)
	)
	(wire
		(pts
			(xy 204.47 246.38) (xy 204.47 250.19)
		)
		(stroke
			(width 0)
			(type default)
		)
	)
	(wire
		(pts
			(xy 210.82 237.49) (xy 210.82 238.76)
		)
		(stroke
			(width 0)
			(type default)
		)
	)
	(wire
		(pts
			(xy 297.18 80.01) (xy 316.23 80.01)
		)
		(stroke
			(width 0)
			(type default)
		)
	)
	(polyline
		(pts
			(xy 354.33 138.43) (xy 353.695 139.065)
		)
		(stroke
			(width 0)
			(type default)
		)
	)
	(wire
		(pts
			(xy 204.47 237.49) (xy 204.47 241.3)
		)
		(stroke
			(width 0)
			(type default)
		)
	)
	(bus
		(pts
			(xy 196.85 77.47) (xy 199.39 77.47)
		)
		(stroke
			(width 0)
			(type default)
		)
	)
	(wire
		(pts
			(xy 227.33 58.42) (xy 227.33 59.69)
		)
		(stroke
			(width 0)
			(type default)
		)
	)
	(wire
		(pts
			(xy 313.69 88.9) (xy 313.69 77.47)
		)
		(stroke
			(width 0)
			(type default)
		)
	)
	(wire
		(pts
			(xy 208.28 237.49) (xy 204.47 237.49)
		)
		(stroke
			(width 0)
			(type default)
		)
	)
	(wire
		(pts
			(xy 240.03 74.93) (xy 241.3 74.93)
		)
		(stroke
			(width 0)
			(type default)
		)
	)
	(wire
		(pts
			(xy 204.47 208.28) (xy 204.47 212.09)
		)
		(stroke
			(width 0)
			(type default)
		)
	)
	(wire
		(pts
			(xy 88.9 127) (xy 96.52 127)
		)
		(stroke
			(width 0)
			(type default)
		)
	)
	(polyline
		(pts
			(xy 353.06 133.35) (xy 353.695 132.715)
		)
		(stroke
			(width 0)
			(type default)
		)
	)
	(wire
		(pts
			(xy 210.82 220.98) (xy 210.82 219.71)
		)
		(stroke
			(width 0)
			(type default)
		)
	)
	(wire
		(pts
			(xy 210.82 49.53) (xy 227.33 49.53)
		)
		(stroke
			(width 0)
			(type default)
		)
	)
	(wire
		(pts
			(xy 322.58 142.24) (xy 342.9 142.24)
		)
		(stroke
			(width 0)
			(type default)
		)
	)
	(wire
		(pts
			(xy 212.09 54.61) (xy 212.09 59.69)
		)
		(stroke
			(width 0)
			(type default)
		)
	)
	(wire
		(pts
			(xy 218.44 137.16) (xy 218.44 142.24)
		)
		(stroke
			(width 0)
			(type default)
		)
	)
	(wire
		(pts
			(xy 95.25 148.59) (xy 95.25 151.13)
		)
		(stroke
			(width 0)
			(type default)
		)
	)
	(wire
		(pts
			(xy 86.36 92.71) (xy 86.36 91.44)
		)
		(stroke
			(width 0)
			(type default)
		)
	)
	(wire
		(pts
			(xy 48.26 30.48) (xy 58.42 30.48)
		)
		(stroke
			(width 0)
			(type default)
		)
	)
	(wire
		(pts
			(xy 347.98 129.54) (xy 375.92 129.54)
		)
		(stroke
			(width 0)
			(type default)
		)
	)
	(wire
		(pts
			(xy 190.5 60.96) (xy 190.5 62.23)
		)
		(stroke
			(width 0)
			(type default)
		)
	)
	(wire
		(pts
			(xy 219.71 87.63) (xy 222.25 87.63)
		)
		(stroke
			(width 0)
			(type default)
		)
	)
	(wire
		(pts
			(xy 30.48 142.24) (xy 46.99 142.24)
		)
		(stroke
			(width 0)
			(type default)
		)
	)
	(wire
		(pts
			(xy 76.2 30.48) (xy 76.2 31.75)
		)
		(stroke
			(width 0)
			(type default)
		)
	)
	(bus
		(pts
			(xy 72.39 58.42) (xy 73.66 59.69)
		)
		(stroke
			(width 0)
			(type default)
		)
	)
	(wire
		(pts
			(xy 274.32 44.45) (xy 274.32 54.61)
		)
		(stroke
			(width 0)
			(type default)
		)
	)
	(wire
		(pts
			(xy 76.2 30.48) (xy 83.82 30.48)
		)
		(stroke
			(width 0)
			(type default)
		)
	)
	(bus
		(pts
			(xy 175.26 139.7) (xy 176.53 140.97)
		)
		(stroke
			(width 0)
			(type default)
		)
	)
	(polyline
		(pts
			(xy 354.33 128.27) (xy 353.695 128.905)
		)
		(stroke
			(width 0)
			(type default)
		)
	)
	(wire
		(pts
			(xy 300.99 129.54) (xy 300.99 123.19)
		)
		(stroke
			(width 0)
			(type default)
		)
	)
	(wire
		(pts
			(xy 240.03 85.09) (xy 241.3 85.09)
		)
		(stroke
			(width 0)
			(type default)
		)
	)
	(polyline
		(pts
			(xy 353.695 140.335) (xy 353.695 141.605)
		)
		(stroke
			(width 0)
			(type default)
		)
	)
	(wire
		(pts
			(xy 316.23 49.53) (xy 316.23 53.34)
		)
		(stroke
			(width 0)
			(type default)
		)
	)
	(wire
		(pts
			(xy 208.28 208.28) (xy 208.28 209.55)
		)
		(stroke
			(width 0)
			(type default)
		)
	)
	(wire
		(pts
			(xy 91.44 124.46) (xy 95.25 124.46)
		)
		(stroke
			(width 0)
			(type default)
		)
	)
	(wire
		(pts
			(xy 88.9 134.62) (xy 88.9 135.89)
		)
		(stroke
			(width 0)
			(type default)
		)
	)
	(wire
		(pts
			(xy 204.47 220.98) (xy 208.28 220.98)
		)
		(stroke
			(width 0)
			(type default)
		)
	)
	(bus
		(pts
			(xy 176.53 140.97) (xy 176.53 143.51)
		)
		(stroke
			(width 0)
			(type default)
		)
	)
	(wire
		(pts
			(xy 297.18 82.55) (xy 318.77 82.55)
		)
		(stroke
			(width 0)
			(type default)
		)
	)
	(bus
		(pts
			(xy 281.94 137.16) (xy 284.48 137.16)
		)
		(stroke
			(width 0)
			(type default)
		)
	)
	(polyline
		(pts
			(xy 354.33 143.51) (xy 353.695 144.145)
		)
		(stroke
			(width 0)
			(type default)
		)
	)
	(wire
		(pts
			(xy 322.58 139.7) (xy 342.9 139.7)
		)
		(stroke
			(width 0)
			(type default)
		)
	)
	(wire
		(pts
			(xy 102.87 149.86) (xy 102.87 148.59)
		)
		(stroke
			(width 0)
			(type default)
		)
	)
	(wire
		(pts
			(xy 264.16 38.1) (xy 274.32 38.1)
		)
		(stroke
			(width 0)
			(type default)
		)
	)
	(wire
		(pts
			(xy 323.85 152.4) (xy 323.85 153.67)
		)
		(stroke
			(width 0)
			(type default)
		)
	)
	(wire
		(pts
			(xy 58.42 30.48) (xy 58.42 31.75)
		)
		(stroke
			(width 0)
			(type default)
		)
	)
	(wire
		(pts
			(xy 227.33 49.53) (xy 227.33 53.34)
		)
		(stroke
			(width 0)
			(type default)
		)
	)
	(wire
		(pts
			(xy 274.32 54.61) (xy 279.4 54.61)
		)
		(stroke
			(width 0)
			(type default)
		)
	)
	(wire
		(pts
			(xy 53.34 208.28) (xy 53.34 209.55)
		)
		(stroke
			(width 0)
			(type default)
		)
	)
	(wire
		(pts
			(xy 227.33 80.01) (xy 241.3 80.01)
		)
		(stroke
			(width 0)
			(type default)
		)
	)
	(wire
		(pts
			(xy 40.64 125.73) (xy 40.64 127)
		)
		(stroke
			(width 0)
			(type default)
		)
	)
	(wire
		(pts
			(xy 257.81 54.61) (xy 274.32 54.61)
		)
		(stroke
			(width 0)
			(type default)
		)
	)
	(wire
		(pts
			(xy 87.63 53.34) (xy 83.82 53.34)
		)
		(stroke
			(width 0)
			(type default)
		)
	)
	(wire
		(pts
			(xy 194.31 49.53) (xy 194.31 38.1)
		)
		(stroke
			(width 0)
			(type default)
		)
	)
	(wire
		(pts
			(xy 93.98 229.87) (xy 93.98 231.14)
		)
		(stroke
			(width 0)
			(type default)
		)
	)
	(polyline
		(pts
			(xy 353.695 140.97) (xy 354.33 140.97)
		)
		(stroke
			(width 0)
			(type default)
		)
	)
	(wire
		(pts
			(xy 114.3 127) (xy 114.3 147.32)
		)
		(stroke
			(width 0)
			(type default)
		)
	)
	(wire
		(pts
			(xy 86.36 91.44) (xy 87.63 91.44)
		)
		(stroke
			(width 0)
			(type default)
		)
	)
	(wire
		(pts
			(xy 311.15 88.9) (xy 311.15 87.63)
		)
		(stroke
			(width 0)
			(type default)
		)
	)
	(wire
		(pts
			(xy 177.8 144.78) (xy 194.31 144.78)
		)
		(stroke
			(width 0)
			(type default)
		)
	)
	(wire
		(pts
			(xy 316.23 64.77) (xy 316.23 66.04)
		)
		(stroke
			(width 0)
			(type default)
		)
	)
	(wire
		(pts
			(xy 116.84 149.86) (xy 116.84 151.13)
		)
		(stroke
			(width 0)
			(type default)
		)
	)
	(wire
		(pts
			(xy 116.84 149.86) (xy 118.11 149.86)
		)
		(stroke
			(width 0)
			(type default)
		)
	)
	(polyline
		(pts
			(xy 353.06 135.89) (xy 353.695 136.525)
		)
		(stroke
			(width 0)
			(type default)
		)
	)
	(wire
		(pts
			(xy 210.82 220.98) (xy 210.82 222.25)
		)
		(stroke
			(width 0)
			(type default)
		)
	)
	(wire
		(pts
			(xy 299.72 54.61) (xy 300.99 54.61)
		)
		(stroke
			(width 0)
			(type default)
		)
	)
	(wire
		(pts
			(xy 35.56 144.78) (xy 46.99 144.78)
		)
		(stroke
			(width 0)
			(type default)
		)
	)
	(wire
		(pts
			(xy 86.36 91.44) (xy 86.36 88.9)
		)
		(stroke
			(width 0)
			(type default)
		)
	)
	(polyline
		(pts
			(xy 353.06 135.89) (xy 353.695 135.255)
		)
		(stroke
			(width 0)
			(type default)
		)
	)
	(polyline
		(pts
			(xy 353.06 140.97) (xy 353.695 140.335)
		)
		(stroke
			(width 0)
			(type default)
		)
	)
	(wire
		(pts
			(xy 347.98 147.32) (xy 356.87 147.32)
		)
		(stroke
			(width 0)
			(type default)
		)
	)
	(wire
		(pts
			(xy 185.42 54.61) (xy 190.5 54.61)
		)
		(stroke
			(width 0)
			(type default)
		)
	)
	(wire
		(pts
			(xy 204.47 200.66) (xy 204.47 201.93)
		)
		(stroke
			(width 0)
			(type default)
		)
	)
	(bus
		(pts
			(xy 285.75 138.43) (xy 285.75 140.97)
		)
		(stroke
			(width 0)
			(type default)
		)
	)
	(wire
		(pts
			(xy 71.12 247.65) (xy 88.9 247.65)
		)
		(stroke
			(width 0)
			(type default)
		)
	)
	(wire
		(pts
			(xy 347.98 137.16) (xy 375.92 137.16)
		)
		(stroke
			(width 0)
			(type default)
		)
	)
	(wire
		(pts
			(xy 83.82 50.8) (xy 87.63 50.8)
		)
		(stroke
			(width 0)
			(type default)
		)
	)
	(wire
		(pts
			(xy 198.12 151.13) (xy 196.85 151.13)
		)
		(stroke
			(width 0)
			(type default)
		)
	)
	(wire
		(pts
			(xy 232.41 146.05) (xy 232.41 147.32)
		)
		(stroke
			(width 0)
			(type default)
		)
	)
	(wire
		(pts
			(xy 213.36 153.67) (xy 218.44 153.67)
		)
		(stroke
			(width 0)
			(type default)
		)
	)
	(wire
		(pts
			(xy 204.47 207.01) (xy 204.47 208.28)
		)
		(stroke
			(width 0)
			(type default)
		)
	)
	(wire
		(pts
			(xy 107.95 144.78) (xy 107.95 149.86)
		)
		(stroke
			(width 0)
			(type default)
		)
	)
	(wire
		(pts
			(xy 218.44 147.32) (xy 218.44 153.67)
		)
		(stroke
			(width 0)
			(type default)
		)
	)
	(polyline
		(pts
			(xy 353.695 132.715) (xy 353.695 133.985)
		)
		(stroke
			(width 0)
			(type default)
		)
	)
	(wire
		(pts
			(xy 73.66 133.35) (xy 73.66 132.08)
		)
		(stroke
			(width 0)
			(type default)
		)
	)
	(wire
		(pts
			(xy 208.28 220.98) (xy 210.82 220.98)
		)
		(stroke
			(width 0)
			(type default)
		)
	)
	(wire
		(pts
			(xy 204.47 217.17) (xy 204.47 220.98)
		)
		(stroke
			(width 0)
			(type default)
		)
	)
	(wire
		(pts
			(xy 322.58 132.08) (xy 342.9 132.08)
		)
		(stroke
			(width 0)
			(type default)
		)
	)
	(wire
		(pts
			(xy 290.83 124.46) (xy 290.83 123.19)
		)
		(stroke
			(width 0)
			(type default)
		)
	)
	(wire
		(pts
			(xy 48.26 30.48) (xy 48.26 31.75)
		)
		(stroke
			(width 0)
			(type default)
		)
	)
	(wire
		(pts
			(xy 201.93 80.01) (xy 227.33 80.01)
		)
		(stroke
			(width 0)
			(type default)
		)
	)
	(wire
		(pts
			(xy 100.33 148.59) (xy 102.87 148.59)
		)
		(stroke
			(width 0)
			(type default)
		)
	)
	(polyline
		(pts
			(xy 354.33 138.43) (xy 353.695 137.795)
		)
		(stroke
			(width 0)
			(type default)
		)
	)
	(wire
		(pts
			(xy 316.23 80.01) (xy 316.23 88.9)
		)
		(stroke
			(width 0)
			(type default)
		)
	)
	(wire
		(pts
			(xy 175.26 38.1) (xy 185.42 38.1)
		)
		(stroke
			(width 0)
			(type default)
		)
	)
	(wire
		(pts
			(xy 114.3 147.32) (xy 118.11 147.32)
		)
		(stroke
			(width 0)
			(type default)
		)
	)
	(wire
		(pts
			(xy 300.99 146.05) (xy 302.26 146.05)
		)
		(stroke
			(width 0)
			(type default)
		)
	)
	(wire
		(pts
			(xy 71.12 255.27) (xy 88.9 255.27)
		)
		(stroke
			(width 0)
			(type default)
		)
	)
	(wire
		(pts
			(xy 313.69 77.47) (xy 326.39 77.47)
		)
		(stroke
			(width 0)
			(type default)
		)
	)
	(wire
		(pts
			(xy 204.47 229.87) (xy 204.47 231.14)
		)
		(stroke
			(width 0)
			(type default)
		)
	)
	(wire
		(pts
			(xy 302.26 132.08) (xy 300.99 132.08)
		)
		(stroke
			(width 0)
			(type default)
		)
	)
	(wire
		(pts
			(xy 210.82 54.61) (xy 212.09 54.61)
		)
		(stroke
			(width 0)
			(type default)
		)
	)
	(bus
		(pts
			(xy 294.64 77.47) (xy 295.91 78.74)
		)
		(stroke
			(width 0)
			(type default)
		)
	)
	(wire
		(pts
			(xy 283.21 49.53) (xy 283.21 38.1)
		)
		(stroke
			(width 0)
			(type default)
		)
	)
	(wire
		(pts
			(xy 78.74 69.85) (xy 78.74 71.12)
		)
		(stroke
			(width 0)
			(type default)
		)
	)
	(polyline
		(pts
			(xy 353.695 135.89) (xy 354.33 135.89)
		)
		(stroke
			(width 0)
			(type default)
		)
	)
	(wire
		(pts
			(xy 300.99 129.54) (xy 302.26 129.54)
		)
		(stroke
			(width 0)
			(type default)
		)
	)
	(wire
		(pts
			(xy 218.44 153.67) (xy 218.44 154.94)
		)
		(stroke
			(width 0)
			(type default)
		)
	)
	(wire
		(pts
			(xy 278.13 135.89) (xy 302.26 135.89)
		)
		(stroke
			(width 0)
			(type default)
		)
	)
	(wire
		(pts
			(xy 279.4 54.61) (xy 279.4 55.88)
		)
		(stroke
			(width 0)
			(type default)
		)
	)
	(wire
		(pts
			(xy 201.93 82.55) (xy 229.87 82.55)
		)
		(stroke
			(width 0)
			(type default)
		)
	)
	(wire
		(pts
			(xy 300.99 151.13) (xy 300.99 149.86)
		)
		(stroke
			(width 0)
			(type default)
		)
	)
	(wire
		(pts
			(xy 217.17 59.69) (xy 217.17 58.42)
		)
		(stroke
			(width 0)
			(type default)
		)
	)
	(wire
		(pts
			(xy 210.82 208.28) (xy 231.14 208.28)
		)
		(stroke
			(width 0)
			(type default)
		)
	)
	(wire
		(pts
			(xy 210.82 250.19) (xy 210.82 248.92)
		)
		(stroke
			(width 0)
			(type default)
		)
	)
	(wire
		(pts
			(xy 198.12 153.67) (xy 196.85 153.67)
		)
		(stroke
			(width 0)
			(type default)
		)
	)
	(wire
		(pts
			(xy 347.98 139.7) (xy 364.49 139.7)
		)
		(stroke
			(width 0)
			(type default)
		)
	)
	(wire
		(pts
			(xy 74.93 60.96) (xy 87.63 60.96)
		)
		(stroke
			(width 0)
			(type default)
		)
	)
	(wire
		(pts
			(xy 73.66 125.73) (xy 73.66 127)
		)
		(stroke
			(width 0)
			(type default)
		)
	)
	(bus
		(pts
			(xy 295.91 78.74) (xy 295.91 81.28)
		)
		(stroke
			(width 0)
			(type default)
		)
	)
	(wire
		(pts
			(xy 78.74 77.47) (xy 78.74 76.2)
		)
		(stroke
			(width 0)
			(type default)
		)
	)
	(wire
		(pts
			(xy 316.23 80.01) (xy 330.2 80.01)
		)
		(stroke
			(width 0)
			(type default)
		)
	)
	(wire
		(pts
			(xy 78.74 77.47) (xy 85.09 77.47)
		)
		(stroke
			(width 0)
			(type default)
		)
	)
	(wire
		(pts
			(xy 27.94 142.24) (xy 30.48 142.24)
		)
		(stroke
			(width 0)
			(type default)
		)
	)
	(wire
		(pts
			(xy 185.42 44.45) (xy 185.42 54.61)
		)
		(stroke
			(width 0)
			(type default)
		)
	)
	(wire
		(pts
			(xy 322.58 147.32) (xy 342.9 147.32)
		)
		(stroke
			(width 0)
			(type default)
		)
	)
	(wire
		(pts
			(xy 86.36 127) (xy 88.9 127)
		)
		(stroke
			(width 0)
			(type default)
		)
	)
	(bus
		(pts
			(xy 69.85 246.38) (xy 69.85 248.92)
		)
		(stroke
			(width 0)
			(type default)
		)
	)
	(bus
		(pts
			(xy 381 125.73) (xy 378.46 125.73)
		)
		(stroke
			(width 0)
			(type default)
		)
	)
	(wire
		(pts
			(xy 322.58 152.4) (xy 323.85 152.4)
		)
		(stroke
			(width 0)
			(type default)
		)
	)
	(wire
		(pts
			(xy 68.58 139.7) (xy 68.58 125.73)
		)
		(stroke
			(width 0)
			(type default)
		)
	)
	(wire
		(pts
			(xy 175.26 36.83) (xy 175.26 38.1)
		)
		(stroke
			(width 0)
			(type default)
		)
	)
	(wire
		(pts
			(xy 40.64 132.08) (xy 40.64 134.62)
		)
		(stroke
			(width 0)
			(type default)
		)
	)
	(wire
		(pts
			(xy 328.93 85.09) (xy 330.2 85.09)
		)
		(stroke
			(width 0)
			(type default)
		)
	)
	(wire
		(pts
			(xy 166.37 54.61) (xy 185.42 54.61)
		)
		(stroke
			(width 0)
			(type default)
		)
	)
	(wire
		(pts
			(xy 57.15 66.04) (xy 87.63 66.04)
		)
		(stroke
			(width 0)
			(type default)
		)
	)
	(wire
		(pts
			(xy 105.41 142.24) (xy 105.41 149.86)
		)
		(stroke
			(width 0)
			(type default)
		)
	)
	(wire
		(pts
			(xy 241.3 77.47) (xy 237.49 77.47)
		)
		(stroke
			(width 0)
			(type default)
		)
	)
	(wire
		(pts
			(xy 44.45 229.87) (xy 44.45 231.14)
		)
		(stroke
			(width 0)
			(type default)
		)
	)
	(polyline
		(pts
			(xy 354.33 130.81) (xy 353.695 131.445)
		)
		(stroke
			(width 0)
			(type default)
		)
	)
	(bus
		(pts
			(xy 377.19 127) (xy 377.19 128.27)
		)
		(stroke
			(width 0)
			(type default)
		)
	)
	(wire
		(pts
			(xy 290.83 129.54) (xy 290.83 130.81)
		)
		(stroke
			(width 0)
			(type default)
		)
	)
	(wire
		(pts
			(xy 208.28 208.28) (xy 204.47 208.28)
		)
		(stroke
			(width 0)
			(type default)
		)
	)
	(wire
		(pts
			(xy 264.16 38.1) (xy 264.16 39.37)
		)
		(stroke
			(width 0)
			(type default)
		)
	)
	(wire
		(pts
			(xy 318.77 82.55) (xy 330.2 82.55)
		)
		(stroke
			(width 0)
			(type default)
		)
	)
	(wire
		(pts
			(xy 74.93 63.5) (xy 87.63 63.5)
		)
		(stroke
			(width 0)
			(type default)
		)
	)
	(wire
		(pts
			(xy 322.58 137.16) (xy 342.9 137.16)
		)
		(stroke
			(width 0)
			(type default)
		)
	)
	(polyline
		(pts
			(xy 12.065 106.68) (xy 408.305 106.68)
		)
		(stroke
			(width 0)
			(type default)
		)
	)
	(wire
		(pts
			(xy 227.33 49.53) (xy 237.49 49.53)
		)
		(stroke
			(width 0)
			(type default)
		)
	)
	(wire
		(pts
			(xy 67.31 77.47) (xy 78.74 77.47)
		)
		(stroke
			(width 0)
			(type default)
		)
	)
	(wire
		(pts
			(xy 287.02 142.24) (xy 302.26 142.24)
		)
		(stroke
			(width 0)
			(type default)
		)
	)
	(wire
		(pts
			(xy 93.98 224.79) (xy 93.98 223.52)
		)
		(stroke
			(width 0)
			(type default)
		)
	)
	(wire
		(pts
			(xy 308.61 87.63) (xy 308.61 88.9)
		)
		(stroke
			(width 0)
			(type default)
		)
	)
	(wire
		(pts
			(xy 194.31 49.53) (xy 195.58 49.53)
		)
		(stroke
			(width 0)
			(type default)
		)
	)
	(wire
		(pts
			(xy 53.34 214.63) (xy 53.34 215.9)
		)
		(stroke
			(width 0)
			(type default)
		)
	)
	(wire
		(pts
			(xy 316.23 58.42) (xy 316.23 59.69)
		)
		(stroke
			(width 0)
			(type default)
		)
	)
	(wire
		(pts
			(xy 86.36 123.19) (xy 86.36 127)
		)
		(stroke
			(width 0)
			(type default)
		)
	)
	(wire
		(pts
			(xy 45.72 139.7) (xy 45.72 125.73)
		)
		(stroke
			(width 0)
			(type default)
		)
	)
	(wire
		(pts
			(xy 175.26 44.45) (xy 175.26 45.72)
		)
		(stroke
			(width 0)
			(type default)
		)
	)
	(wire
		(pts
			(xy 190.5 54.61) (xy 190.5 55.88)
		)
		(stroke
			(width 0)
			(type default)
		)
	)
	(bus
		(pts
			(xy 69.85 251.46) (xy 69.85 254)
		)
		(stroke
			(width 0)
			(type default)
		)
	)
	(wire
		(pts
			(xy 196.85 151.13) (xy 196.85 153.67)
		)
		(stroke
			(width 0)
			(type default)
		)
	)
	(wire
		(pts
			(xy 68.58 151.13) (xy 68.58 147.32)
		)
		(stroke
			(width 0)
			(type default)
		)
	)
	(wire
		(pts
			(xy 110.49 149.86) (xy 110.49 148.59)
		)
		(stroke
			(width 0)
			(type default)
		)
	)
	(polyline
		(pts
			(xy 12.065 173.355) (xy 408.305 173.355)
		)
		(stroke
			(width 0)
			(type default)
		)
	)
	(wire
		(pts
			(xy 194.31 38.1) (xy 185.42 38.1)
		)
		(stroke
			(width 0)
			(type default)
		)
	)
	(wire
		(pts
			(xy 210.82 208.28) (xy 210.82 209.55)
		)
		(stroke
			(width 0)
			(type default)
		)
	)
	(wire
		(pts
			(xy 190.5 54.61) (xy 195.58 54.61)
		)
		(stroke
			(width 0)
			(type default)
		)
	)
	(wire
		(pts
			(xy 91.44 123.19) (xy 91.44 124.46)
		)
		(stroke
			(width 0)
			(type default)
		)
	)
	(wire
		(pts
			(xy 177.8 142.24) (xy 191.77 142.24)
		)
		(stroke
			(width 0)
			(type default)
		)
	)
	(wire
		(pts
			(xy 229.87 82.55) (xy 241.3 82.55)
		)
		(stroke
			(width 0)
			(type default)
		)
	)
	(wire
		(pts
			(xy 45.72 125.73) (xy 40.64 125.73)
		)
		(stroke
			(width 0)
			(type default)
		)
	)
	(wire
		(pts
			(xy 316.23 49.53) (xy 326.39 49.53)
		)
		(stroke
			(width 0)
			(type default)
		)
	)
	(wire
		(pts
			(xy 86.36 88.9) (xy 87.63 88.9)
		)
		(stroke
			(width 0)
			(type default)
		)
	)
	(wire
		(pts
			(xy 306.07 52.07) (xy 306.07 53.34)
		)
		(stroke
			(width 0)
			(type default)
		)
	)
	(polyline
		(pts
			(xy 353.695 135.255) (xy 353.695 136.525)
		)
		(stroke
			(width 0)
			(type default)
		)
	)
	(wire
		(pts
			(xy 85.09 77.47) (xy 85.09 71.12)
		)
		(stroke
			(width 0)
			(type default)
		)
	)
	(wire
		(pts
			(xy 102.87 226.06) (xy 102.87 231.14)
		)
		(stroke
			(width 0)
			(type default)
		)
	)
	(polyline
		(pts
			(xy 151.765 12.7) (xy 151.765 284.48)
		)
		(stroke
			(width 0)
			(type default)
		)
	)
	(wire
		(pts
			(xy 67.31 30.48) (xy 76.2 30.48)
		)
		(stroke
			(width 0)
			(type default)
		)
	)
	(wire
		(pts
			(xy 86.36 86.36) (xy 87.63 86.36)
		)
		(stroke
			(width 0)
			(type default)
		)
	)
	(wire
		(pts
			(xy 222.25 88.9) (xy 222.25 87.63)
		)
		(stroke
			(width 0)
			(type default)
		)
	)
	(polyline
		(pts
			(xy 353.695 143.51) (xy 353.06 143.51)
		)
		(stroke
			(width 0)
			(type default)
		)
	)
	(wire
		(pts
			(xy 208.28 237.49) (xy 210.82 237.49)
		)
		(stroke
			(width 0)
			(type default)
		)
	)
	(polyline
		(pts
			(xy 354.33 130.81) (xy 353.695 130.175)
		)
		(stroke
			(width 0)
			(type default)
		)
	)
	(wire
		(pts
			(xy 240.03 86.36) (xy 240.03 85.09)
		)
		(stroke
			(width 0)
			(type default)
		)
	)
	(wire
		(pts
			(xy 326.39 49.53) (xy 326.39 77.47)
		)
		(stroke
			(width 0)
			(type default)
		)
	)
	(wire
		(pts
			(xy 278.13 121.92) (xy 278.13 124.46)
		)
		(stroke
			(width 0)
			(type default)
		)
	)
	(wire
		(pts
			(xy 229.87 88.9) (xy 229.87 82.55)
		)
		(stroke
			(width 0)
			(type default)
		)
	)
	(polyline
		(pts
			(xy 353.695 131.445) (xy 353.695 130.175)
		)
		(stroke
			(width 0)
			(type default)
		)
	)
	(wire
		(pts
			(xy 294.64 146.05) (xy 295.91 146.05)
		)
		(stroke
			(width 0)
			(type default)
		)
	)
	(wire
		(pts
			(xy 347.98 132.08) (xy 375.92 132.08)
		)
		(stroke
			(width 0)
			(type default)
		)
	)
	(wire
		(pts
			(xy 299.72 52.07) (xy 306.07 52.07)
		)
		(stroke
			(width 0)
			(type default)
		)
	)
	(wire
		(pts
			(xy 101.6 124.46) (xy 114.3 124.46)
		)
		(stroke
			(width 0)
			(type default)
		)
	)
	(bus
		(pts
			(xy 284.48 137.16) (xy 285.75 138.43)
		)
		(stroke
			(width 0)
			(type default)
		)
	)
	(wire
		(pts
			(xy 93.98 220.98) (xy 93.98 223.52)
		)
		(stroke
			(width 0)
			(type default)
		)
	)
	(polyline
		(pts
			(xy 354.33 128.27) (xy 353.695 127.635)
		)
		(stroke
			(width 0)
			(type default)
		)
	)
	(wire
		(pts
			(xy 95.25 124.46) (xy 95.25 129.54)
		)
		(stroke
			(width 0)
			(type default)
		)
	)
	(wire
		(pts
			(xy 102.87 201.93) (xy 102.87 203.2)
		)
		(stroke
			(width 0)
			(type default)
		)
	)
	(bus
		(pts
			(xy 200.66 78.74) (xy 200.66 81.28)
		)
		(stroke
			(width 0)
			(type default)
		)
	)
	(wire
		(pts
			(xy 232.41 139.7) (xy 232.41 140.97)
		)
		(stroke
			(width 0)
			(type default)
		)
	)
	(wire
		(pts
			(xy 279.4 60.96) (xy 279.4 62.23)
		)
		(stroke
			(width 0)
			(type default)
		)
	)
	(wire
		(pts
			(xy 57.15 64.77) (xy 57.15 66.04)
		)
		(stroke
			(width 0)
			(type default)
		)
	)
	(wire
		(pts
			(xy 185.42 38.1) (xy 185.42 39.37)
		)
		(stroke
			(width 0)
			(type default)
		)
	)
	(wire
		(pts
			(xy 58.42 38.1) (xy 58.42 36.83)
		)
		(stroke
			(width 0)
			(type default)
		)
	)
	(wire
		(pts
			(xy 330.2 77.47) (xy 326.39 77.47)
		)
		(stroke
			(width 0)
			(type default)
		)
	)
	(wire
		(pts
			(xy 210.82 250.19) (xy 210.82 251.46)
		)
		(stroke
			(width 0)
			(type default)
		)
	)
	(wire
		(pts
			(xy 93.98 223.52) (xy 96.52 223.52)
		)
		(stroke
			(width 0)
			(type default)
		)
	)
	(wire
		(pts
			(xy 57.15 58.42) (xy 57.15 59.69)
		)
		(stroke
			(width 0)
			(type default)
		)
	)
	(polyline
		(pts
			(xy 353.695 130.81) (xy 353.06 130.81)
		)
		(stroke
			(width 0)
			(type default)
		)
	)
	(wire
		(pts
			(xy 227.33 64.77) (xy 227.33 66.04)
		)
		(stroke
			(width 0)
			(type default)
		)
	)
	(wire
		(pts
			(xy 208.28 248.92) (xy 208.28 250.19)
		)
		(stroke
			(width 0)
			(type default)
		)
	)
	(wire
		(pts
			(xy 219.71 87.63) (xy 219.71 88.9)
		)
		(stroke
			(width 0)
			(type default)
		)
	)
	(wire
		(pts
			(xy 45.72 139.7) (xy 46.99 139.7)
		)
		(stroke
			(width 0)
			(type default)
		)
	)
	(wire
		(pts
			(xy 299.72 49.53) (xy 316.23 49.53)
		)
		(stroke
			(width 0)
			(type default)
		)
	)
	(bus
		(pts
			(xy 68.58 245.11) (xy 69.85 246.38)
		)
		(stroke
			(width 0)
			(type default)
		)
	)
	(wire
		(pts
			(xy 86.36 88.9) (xy 86.36 86.36)
		)
		(stroke
			(width 0)
			(type default)
		)
	)
	(wire
		(pts
			(xy 322.58 134.62) (xy 342.9 134.62)
		)
		(stroke
			(width 0)
			(type default)
		)
	)
	(wire
		(pts
			(xy 107.95 144.78) (xy 118.11 144.78)
		)
		(stroke
			(width 0)
			(type default)
		)
	)
	(label "CAM_CTRL.CSIA_FLG"
		(at 355.6 134.62 0)
		(effects
			(font
				(size 1.27 1.27)
			)
			(justify left bottom)
		)
	)
	(label "GPIO.USER_LED0"
		(at 88.9 247.65 180)
		(effects
			(font
				(size 1.27 1.27)
			)
			(justify right bottom)
		)
	)
	(label "GPIO.USER_BTN0"
		(at 231.14 208.28 180)
		(effects
			(font
				(size 1.27 1.27)
			)
			(justify right bottom)
		)
	)
	(label "TPM_RST"
		(at 40.64 74.93 0)
		(effects
			(font
				(size 1.27 1.27)
			)
			(justify left bottom)
		)
	)
	(label "GPIOEX_P0_4"
		(at 323.85 139.7 0)
		(effects
			(font
				(size 1.27 1.27)
			)
			(justify left bottom)
		)
	)
	(label "CAM_CTRL.CSIA_PEN"
		(at 355.6 129.54 0)
		(effects
			(font
				(size 1.27 1.27)
			)
			(justify left bottom)
		)
	)
	(label "GPIO.USER_BTN0"
		(at 88.9 252.73 180)
		(effects
			(font
				(size 1.27 1.27)
			)
			(justify right bottom)
		)
	)
	(label "FAN_TACH_5V"
		(at 69.85 144.78 0)
		(effects
			(font
				(size 1.27 1.27)
			)
			(justify left bottom)
		)
	)
	(label "CAM_CTRL.CSIB_FLG"
		(at 355.6 137.16 0)
		(effects
			(font
				(size 1.27 1.27)
			)
			(justify left bottom)
		)
	)
	(label "FAN_PWM_5V"
		(at 69.85 142.24 0)
		(effects
			(font
				(size 1.27 1.27)
			)
			(justify left bottom)
		)
	)
	(label "GPIOEX_P0_7"
		(at 323.85 147.32 0)
		(effects
			(font
				(size 1.27 1.27)
			)
			(justify left bottom)
		)
	)
	(label "GPIOEX_P0_5"
		(at 323.85 142.24 0)
		(effects
			(font
				(size 1.27 1.27)
			)
			(justify left bottom)
		)
	)
	(label "I2C_{CONN}.SCL"
		(at 203.2 82.55 0)
		(effects
			(font
				(size 1.27 1.27)
			)
			(justify left bottom)
		)
	)
	(label "GPIOEX_P0_1"
		(at 323.85 132.08 0)
		(effects
			(font
				(size 1.27 1.27)
			)
			(justify left bottom)
		)
	)
	(label "GPIOEX_P0_3"
		(at 323.85 137.16 0)
		(effects
			(font
				(size 1.27 1.27)
			)
			(justify left bottom)
		)
	)
	(label "TPM_IRQ"
		(at 67.31 77.47 0)
		(effects
			(font
				(size 1.27 1.27)
			)
			(justify left bottom)
		)
	)
	(label "I2C_{SYS}.SDA"
		(at 76.2 63.5 0)
		(effects
			(font
				(size 1.27 1.27)
			)
			(justify left bottom)
		)
	)
	(label "I2C_CONN_PEN"
		(at 257.81 54.61 0)
		(effects
			(font
				(size 1.27 1.27)
			)
			(justify left bottom)
		)
	)
	(label "I2C_{CONN}.SCL"
		(at 299.72 82.55 0)
		(effects
			(font
				(size 1.27 1.27)
			)
			(justify left bottom)
		)
	)
	(label "GPIO.USER_BTN1"
		(at 231.14 237.49 180)
		(effects
			(font
				(size 1.27 1.27)
			)
			(justify right bottom)
		)
	)
	(label "I2C_CONN1_3V3"
		(at 212.09 49.53 0)
		(effects
			(font
				(size 1.27 1.27)
			)
			(justify left bottom)
		)
	)
	(label "GPIO.USER_LED1"
		(at 77.47 220.98 0)
		(effects
			(font
				(size 1.27 1.27)
			)
			(justify left bottom)
		)
	)
	(label "GPIOEX_P0_2"
		(at 323.85 134.62 0)
		(effects
			(font
				(size 1.27 1.27)
			)
			(justify left bottom)
		)
	)
	(label "I2C_{SYS}.SCL"
		(at 179.07 144.78 0)
		(effects
			(font
				(size 1.27 1.27)
			)
			(justify left bottom)
		)
	)
	(label "I2C_CONN_PEN"
		(at 370.84 144.78 180)
		(effects
			(font
				(size 1.27 1.27)
			)
			(justify right bottom)
		)
	)
	(label "I2C_{CONN}.SDA"
		(at 203.2 80.01 0)
		(effects
			(font
				(size 1.27 1.27)
			)
			(justify left bottom)
		)
	)
	(label "GPIO.USER_LED0"
		(at 27.94 220.98 0)
		(effects
			(font
				(size 1.27 1.27)
			)
			(justify left bottom)
		)
	)
	(label "I2C_CONN_PEN"
		(at 166.37 54.61 0)
		(effects
			(font
				(size 1.27 1.27)
			)
			(justify left bottom)
		)
	)
	(label "I2C_{SYS}.SDA"
		(at 288.29 139.7 0)
		(effects
			(font
				(size 1.27 1.27)
			)
			(justify left bottom)
		)
	)
	(label "GPIO.USER_LED1"
		(at 88.9 250.19 180)
		(effects
			(font
				(size 1.27 1.27)
			)
			(justify right bottom)
		)
	)
	(label "I2C_{SYS}.SDA"
		(at 179.07 142.24 0)
		(effects
			(font
				(size 1.27 1.27)
			)
			(justify left bottom)
		)
	)
	(label "I2C_CONN2_3V3"
		(at 300.99 49.53 0)
		(effects
			(font
				(size 1.27 1.27)
			)
			(justify left bottom)
		)
	)
	(label "FAN_VDD"
		(at 106.68 124.46 0)
		(effects
			(font
				(size 1.27 1.27)
			)
			(justify left bottom)
		)
	)
	(label "TPM_IRQ"
		(at 364.49 142.24 180)
		(effects
			(font
				(size 1.27 1.27)
			)
			(justify right bottom)
		)
	)
	(label "I2C_{SYS}.SCL"
		(at 76.2 60.96 0)
		(effects
			(font
				(size 1.27 1.27)
			)
			(justify left bottom)
		)
	)
	(label "GPIO.USER_BTN1"
		(at 88.9 255.27 180)
		(effects
			(font
				(size 1.27 1.27)
			)
			(justify right bottom)
		)
	)
	(label "I2C_{CONN}.SDA"
		(at 299.72 80.01 0)
		(effects
			(font
				(size 1.27 1.27)
			)
			(justify left bottom)
		)
	)
	(label "GPIOEX_P0_6"
		(at 323.85 144.78 0)
		(effects
			(font
				(size 1.27 1.27)
			)
			(justify left bottom)
		)
	)
	(label "GPIOEX_P0_0"
		(at 323.85 129.54 0)
		(effects
			(font
				(size 1.27 1.27)
			)
			(justify left bottom)
		)
	)
	(label "TPM_RST"
		(at 364.49 139.7 180)
		(effects
			(font
				(size 1.27 1.27)
			)
			(justify right bottom)
		)
	)
	(label "CAM_CTRL.CSIB_PEN"
		(at 355.6 132.08 0)
		(effects
			(font
				(size 1.27 1.27)
			)
			(justify left bottom)
		)
	)
	(label "I2C_{SYS}.SCL"
		(at 288.29 142.24 0)
		(effects
			(font
				(size 1.27 1.27)
			)
			(justify left bottom)
		)
	)
	(hierarchical_label "I2C_{CONN}{I2C}"
		(shape bidirectional)
		(at 292.1 77.47 180)
		(effects
			(font
				(size 1.27 1.27)
			)
			(justify right)
		)
	)
	(hierarchical_label "I2C_{SYS}{I2C}"
		(shape bidirectional)
		(at 172.72 139.7 180)
		(effects
			(font
				(size 1.27 1.27)
			)
			(justify right)
		)
	)
	(hierarchical_label "FAN_TACH"
		(shape output)
		(at 27.94 144.78 180)
		(effects
			(font
				(size 1.27 1.27)
			)
			(justify right)
		)
	)
	(hierarchical_label "FAN_PWM"
		(shape input)
		(at 27.94 142.24 180)
		(effects
			(font
				(size 1.27 1.27)
			)
			(justify right)
		)
	)
	(hierarchical_label "I2C_{SYS}{I2C}"
		(shape bidirectional)
		(at 281.94 137.16 180)
		(effects
			(font
				(size 1.27 1.27)
			)
			(justify right)
		)
	)
	(hierarchical_label "I2C_{SYS}{I2C}"
		(shape input)
		(at 72.39 58.42 180)
		(effects
			(font
				(size 1.27 1.27)
			)
			(justify right)
		)
	)
	(hierarchical_label "GPIO_EXP_IRQ"
		(shape output)
		(at 267.97 135.89 180)
		(effects
			(font
				(size 1.27 1.27)
			)
			(justify right)
		)
	)
	(hierarchical_label "I2C_{CONN}{I2C}"
		(shape bidirectional)
		(at 196.85 77.47 180)
		(effects
			(font
				(size 1.27 1.27)
			)
			(justify right)
		)
	)
	(hierarchical_label "CAM_CTRL{CAM_CTRL}"
		(shape bidirectional)
		(at 381 125.73 0)
		(effects
			(font
				(size 1.27 1.27)
			)
			(justify left)
		)
	)
	(hierarchical_label "GPIO{GPIO}"
		(shape bidirectional)
		(at 66.04 245.11 180)
		(effects
			(font
				(size 1.27 1.27)
			)
			(justify right)
		)
	)
	(symbol
		(lib_id "antmicroCapacitors0402:C_100n_0402")
		(at 264.16 39.37 90)
		(mirror x)
		(unit 1)
		(exclude_from_sim no)
		(in_bom yes)
		(on_board yes)
		(dnp no)
		(property "Reference" "C210"
			(at 266.065 40.64 90)
			(effects
				(font
					(size 1.27 1.27)
				)
				(justify right)
			)
		)
		(property "Value" "C_100n_0402"
			(at 274.32 59.69 0)
			(effects
				(font
					(size 1.27 1.27)
					(thickness 0.15)
				)
				(justify left bottom)
				(hide yes)
			)
		)
		(property "Footprint" "antmicro-footprints:C_0402_1005Metric"
			(at 276.86 59.69 0)
			(effects
				(font
					(size 1.27 1.27)
					(thickness 0.15)
				)
				(justify left bottom)
				(hide yes)
			)
		)
		(property "Datasheet" "https://www.murata.com/products/productdetail?partno=GRM155R61H104KE14%23"
			(at 279.4 59.69 0)
			(effects
				(font
					(size 1.27 1.27)
					(thickness 0.15)
				)
				(justify left bottom)
				(hide yes)
			)
		)
		(property "Description" "SMD Multilayer Ceramic Capacitor, 0.1 µF, 50 V, 0402 [1005 Metric], ± 10%, X5R, GRM Series"
			(at 264.16 39.37 0)
			(effects
				(font
					(size 1.27 1.27)
				)
				(hide yes)
			)
		)
		(property "Manufacturer" "Murata"
			(at 284.48 59.69 0)
			(effects
				(font
					(size 1.27 1.27)
					(thickness 0.15)
				)
				(justify left bottom)
				(hide yes)
			)
		)
		(property "MPN" "GRM155R61H104KE14D"
			(at 281.94 59.69 0)
			(effects
				(font
					(size 1.27 1.27)
					(thickness 0.15)
				)
				(justify left bottom)
				(hide yes)
			)
		)
		(property "Val" "100n"
			(at 266.065 43.18 90)
			(effects
				(font
					(size 1.27 1.27)
					(thickness 0.15)
				)
				(justify right)
			)
		)
		(property "License" "Apache-2.0"
			(at 287.02 59.69 0)
			(effects
				(font
					(size 1.27 1.27)
					(thickness 0.15)
				)
				(justify left bottom)
				(hide yes)
			)
		)
		(property "Author" "Antmicro"
			(at 289.56 59.69 0)
			(effects
				(font
					(size 1.27 1.27)
					(thickness 0.15)
				)
				(justify left bottom)
				(hide yes)
			)
		)
		(property "Voltage" "50V"
			(at 292.1 59.69 0)
			(effects
				(font
					(size 1.27 1.27)
				)
				(justify left bottom)
				(hide yes)
			)
		)
		(property "Dielectric" "X5R"
			(at 294.64 59.69 0)
			(effects
				(font
					(size 1.27 1.27)
				)
				(justify left bottom)
				(hide yes)
			)
		)
		(pin "1"
		)
		(pin "2"
		)
		(instances
			(project "jetson-agx-thor-baseboard"
				(path ""
					(reference "C210")
					(unit 1)
				)
			)
		)
	)
	(symbol
		(lib_id "antmicroPushbuttonSwitches:SW_KMR211NGLFS_SMD")
		(at 210.82 209.55 270)
		(unit 1)
		(exclude_from_sim no)
		(in_bom yes)
		(on_board yes)
		(dnp no)
		(property "Reference" "S2"
			(at 214.63 213.36 90)
			(effects
				(font
					(size 1.27 1.27)
				)
				(justify left)
			)
		)
		(property "Value" "SW_KMR211NGLFS_SMD"
			(at 203.2 234.95 0)
			(effects
				(font
					(size 1.27 1.27)
					(thickness 0.15)
				)
				(justify left bottom)
				(hide yes)
			)
		)
		(property "Footprint" "antmicro-footprints:SW_KMR211NGLFS_SMD"
			(at 200.66 234.95 0)
			(effects
				(font
					(size 1.27 1.27)
					(thickness 0.15)
				)
				(justify left bottom)
				(hide yes)
			)
		)
		(property "Datasheet" "http://www.farnell.com/datasheets/2631211.pdf"
			(at 198.12 234.95 0)
			(effects
				(font
					(size 1.27 1.27)
					(thickness 0.15)
				)
				(justify left bottom)
				(hide yes)
			)
		)
		(property "Description" "Tactile Switch, KMR 2 Series, Top Actuated, Surface Mount, Oval Button, 120 gf, 50mA at 32VDC"
			(at 210.82 209.55 0)
			(effects
				(font
					(size 1.27 1.27)
				)
				(hide yes)
			)
		)
		(property "MPN" "KMR211NGLFS"
			(at 214.63 215.9 90)
			(effects
				(font
					(size 1.27 1.27)
					(thickness 0.15)
				)
				(justify left)
			)
		)
		(property "Manufacturer" "C&K"
			(at 195.58 234.95 0)
			(effects
				(font
					(size 1.27 1.27)
					(thickness 0.15)
				)
				(justify left bottom)
				(hide yes)
			)
		)
		(property "Author" "Antmicro"
			(at 193.04 234.95 0)
			(effects
				(font
					(size 1.27 1.27)
					(thickness 0.15)
				)
				(justify left bottom)
				(hide yes)
			)
		)
		(property "License" "Apache-2.0"
			(at 190.5 234.95 0)
			(effects
				(font
					(size 1.27 1.27)
					(thickness 0.15)
				)
				(justify left bottom)
				(hide yes)
			)
		)
		(pin "1"
		)
		(pin "2"
		)
		(pin "3"
		)
		(pin "4"
		)
		(instances
			(project "jetson-agx-thor-baseboard"
				(path ""
					(reference "S2")
					(unit 1)
				)
			)
		)
	)
	(symbol
		(lib_id "antmicroCapacitors0402:C_100n_0402")
		(at 232.41 146.05 90)
		(unit 1)
		(exclude_from_sim no)
		(in_bom yes)
		(on_board yes)
		(dnp no)
		(fields_autoplaced yes)
		(property "Reference" "C209"
			(at 234.95 142.2336 90)
			(effects
				(font
					(size 1.27 1.27)
					(thickness 0.15)
				)
				(justify right)
			)
		)
		(property "Value" "C_100n_0402"
			(at 242.57 125.73 0)
			(effects
				(font
					(size 1.27 1.27)
					(thickness 0.15)
				)
				(justify left bottom)
				(hide yes)
			)
		)
		(property "Footprint" "antmicro-footprints:C_0402_1005Metric"
			(at 245.11 125.73 0)
			(effects
				(font
					(size 1.27 1.27)
					(thickness 0.15)
				)
				(justify left bottom)
				(hide yes)
			)
		)
		(property "Datasheet" "https://www.murata.com/products/productdetail?partno=GRM155R61H104KE14%23"
			(at 247.65 125.73 0)
			(effects
				(font
					(size 1.27 1.27)
					(thickness 0.15)
				)
				(justify left bottom)
				(hide yes)
			)
		)
		(property "Description" "SMD Multilayer Ceramic Capacitor, 0.1 µF, 50 V, 0402 [1005 Metric], ± 10%, X5R, GRM Series"
			(at 232.41 146.05 0)
			(effects
				(font
					(size 1.27 1.27)
				)
				(hide yes)
			)
		)
		(property "MPN" "GRM155R61H104KE14D"
			(at 250.19 125.73 0)
			(effects
				(font
					(size 1.27 1.27)
					(thickness 0.15)
				)
				(justify left bottom)
				(hide yes)
			)
		)
		(property "Manufacturer" "Murata"
			(at 252.73 125.73 0)
			(effects
				(font
					(size 1.27 1.27)
					(thickness 0.15)
				)
				(justify left bottom)
				(hide yes)
			)
		)
		(property "License" "Apache-2.0"
			(at 255.27 125.73 0)
			(effects
				(font
					(size 1.27 1.27)
					(thickness 0.15)
				)
				(justify left bottom)
				(hide yes)
			)
		)
		(property "Author" "Antmicro"
			(at 257.81 125.73 0)
			(effects
				(font
					(size 1.27 1.27)
					(thickness 0.15)
				)
				(justify left bottom)
				(hide yes)
			)
		)
		(property "Val" "100n"
			(at 234.95 144.7736 90)
			(effects
				(font
					(size 1.27 1.27)
					(thickness 0.15)
				)
				(justify right)
			)
		)
		(property "Voltage" "50V"
			(at 260.35 125.73 0)
			(effects
				(font
					(size 1.27 1.27)
				)
				(justify left bottom)
				(hide yes)
			)
		)
		(property "Dielectric" "X5R"
			(at 262.89 125.73 0)
			(effects
				(font
					(size 1.27 1.27)
				)
				(justify left bottom)
				(hide yes)
			)
		)
		(pin "2"
		)
		(pin "1"
		)
		(instances
			(project "jetson-agx-thor-baseboard"
				(path ""
					(reference "C209")
					(unit 1)
				)
			)
		)
	)
	(symbol
		(lib_id "antmicropower:GND")
		(at 48.26 38.1 0)
		(unit 1)
		(exclude_from_sim no)
		(in_bom yes)
		(on_board yes)
		(dnp no)
		(fields_autoplaced yes)
		(property "Reference" "#PWR0387"
			(at 48.26 44.45 0)
			(effects
				(font
					(size 1.27 1.27)
				)
				(justify left bottom)
				(hide yes)
			)
		)
		(property "Value" "GND"
			(at 48.26 41.91 0)
			(effects
				(font
					(size 1.27 1.27)
					(thickness 0.15)
				)
			)
		)
		(property "Footprint" ""
			(at 57.15 45.72 0)
			(effects
				(font
					(size 1.27 1.27)
					(thickness 0.15)
				)
				(justify left bottom)
				(hide yes)
			)
		)
		(property "Datasheet" ""
			(at 57.15 50.8 0)
			(effects
				(font
					(size 1.27 1.27)
					(thickness 0.15)
				)
				(justify left bottom)
				(hide yes)
			)
		)
		(property "Description" ""
			(at 48.26 38.1 0)
			(effects
				(font
					(size 1.27 1.27)
				)
				(hide yes)
			)
		)
		(property "Author" "Antmicro"
			(at 57.15 45.72 0)
			(effects
				(font
					(size 1.27 1.27)
					(thickness 0.15)
				)
				(justify left bottom)
				(hide yes)
			)
		)
		(property "License" "Apache-2.0"
			(at 57.15 48.26 0)
			(effects
				(font
					(size 1.27 1.27)
					(thickness 0.15)
				)
				(justify left bottom)
				(hide yes)
			)
		)
		(pin "1"
		)
		(instances
			(project "jetson-agx-thor-baseboard"
				(path ""
					(reference "#PWR0387")
					(unit 1)
				)
			)
		)
	)
	(symbol
		(lib_id "antmicropower:GND")
		(at 73.66 133.35 0)
		(unit 1)
		(exclude_from_sim no)
		(in_bom yes)
		(on_board yes)
		(dnp no)
		(fields_autoplaced yes)
		(property "Reference" "#PWR0394"
			(at 73.66 139.7 0)
			(effects
				(font
					(size 1.27 1.27)
				)
				(justify left bottom)
				(hide yes)
			)
		)
		(property "Value" "GND"
			(at 73.66 137.16 0)
			(effects
				(font
					(size 1.27 1.27)
					(thickness 0.15)
				)
			)
		)
		(property "Footprint" ""
			(at 82.55 140.97 0)
			(effects
				(font
					(size 1.27 1.27)
					(thickness 0.15)
				)
				(justify left bottom)
				(hide yes)
			)
		)
		(property "Datasheet" ""
			(at 82.55 146.05 0)
			(effects
				(font
					(size 1.27 1.27)
					(thickness 0.15)
				)
				(justify left bottom)
				(hide yes)
			)
		)
		(property "Description" ""
			(at 73.66 133.35 0)
			(effects
				(font
					(size 1.27 1.27)
				)
				(hide yes)
			)
		)
		(property "Author" "Antmicro"
			(at 82.55 140.97 0)
			(effects
				(font
					(size 1.27 1.27)
					(thickness 0.15)
				)
				(justify left bottom)
				(hide yes)
			)
		)
		(property "License" "Apache-2.0"
			(at 82.55 143.51 0)
			(effects
				(font
					(size 1.27 1.27)
					(thickness 0.15)
				)
				(justify left bottom)
				(hide yes)
			)
		)
		(pin "1"
		)
		(instances
			(project "jetson-agx-thor-baseboard"
				(path ""
					(reference "#PWR0394")
					(unit 1)
				)
			)
		)
	)
	(symbol
		(lib_id "antmicropower:GND")
		(at 214.63 90.17 0)
		(unit 1)
		(exclude_from_sim no)
		(in_bom yes)
		(on_board yes)
		(dnp no)
		(property "Reference" "#PWR0411"
			(at 214.63 96.52 0)
			(effects
				(font
					(size 1.27 1.27)
				)
				(justify left bottom)
				(hide yes)
			)
		)
		(property "Value" "GND"
			(at 214.63 93.98 0)
			(effects
				(font
					(size 1.27 1.27)
					(thickness 0.15)
				)
			)
		)
		(property "Footprint" ""
			(at 223.52 97.79 0)
			(effects
				(font
					(size 1.27 1.27)
					(thickness 0.15)
				)
				(justify left bottom)
				(hide yes)
			)
		)
		(property "Datasheet" ""
			(at 223.52 102.87 0)
			(effects
				(font
					(size 1.27 1.27)
					(thickness 0.15)
				)
				(justify left bottom)
				(hide yes)
			)
		)
		(property "Description" ""
			(at 214.63 90.17 0)
			(effects
				(font
					(size 1.27 1.27)
				)
				(hide yes)
			)
		)
		(property "Author" "Antmicro"
			(at 223.52 97.79 0)
			(effects
				(font
					(size 1.27 1.27)
					(thickness 0.15)
				)
				(justify left bottom)
				(hide yes)
			)
		)
		(property "License" "Apache-2.0"
			(at 223.52 100.33 0)
			(effects
				(font
					(size 1.27 1.27)
					(thickness 0.15)
				)
				(justify left bottom)
				(hide yes)
			)
		)
		(pin "1"
		)
		(instances
			(project "jetson-agx-thor-baseboard"
				(path ""
					(reference "#PWR0411")
					(unit 1)
				)
			)
		)
	)
	(symbol
		(lib_id "antmicroTestPoints:TP_0.75mm_SMD")
		(at 356.87 147.32 0)
		(unit 1)
		(exclude_from_sim no)
		(in_bom no)
		(on_board yes)
		(dnp no)
		(property "Reference" "TP71"
			(at 360.934 147.32 0)
			(effects
				(font
					(size 1.27 1.27)
					(thickness 0.15)
				)
				(justify left)
			)
		)
		(property "Value" "TP_0.75mm_SMD"
			(at 367.03 151.13 0)
			(effects
				(font
					(size 1.27 1.27)
					(thickness 0.15)
				)
				(justify left bottom)
				(hide yes)
			)
		)
		(property "Footprint" "antmicro-footprints:TP_SMD_0.75mm"
			(at 367.03 153.67 0)
			(effects
				(font
					(size 1.27 1.27)
					(thickness 0.15)
				)
				(justify left bottom)
				(hide yes)
			)
		)
		(property "Datasheet" ""
			(at 374.65 160.02 0)
			(effects
				(font
					(size 1.27 1.27)
					(thickness 0.15)
				)
				(justify left bottom)
				(hide yes)
			)
		)
		(property "Description" "SMT test point"
			(at 356.87 147.32 0)
			(effects
				(font
					(size 1.27 1.27)
				)
				(hide yes)
			)
		)
		(property "MPN" ""
			(at 367.665 158.75 0)
			(effects
				(font
					(size 1.27 1.27)
					(thickness 0.15)
				)
				(justify left bottom)
				(hide yes)
			)
		)
		(property "Manufacturer" ""
			(at 367.665 153.67 0)
			(effects
				(font
					(size 1.27 1.27)
					(thickness 0.15)
				)
				(justify left bottom)
				(hide yes)
			)
		)
		(property "Author" "Antmicro"
			(at 367.03 156.21 0)
			(effects
				(font
					(size 1.27 1.27)
					(thickness 0.15)
				)
				(justify left bottom)
				(hide yes)
			)
		)
		(property "License" "Apache-2.0"
			(at 367.03 158.75 0)
			(effects
				(font
					(size 1.27 1.27)
					(thickness 0.15)
				)
				(justify left bottom)
				(hide yes)
			)
		)
		(pin "1"
		)
		(instances
			(project "jetson-agx-thor-baseboard"
				(path ""
					(reference "TP71")
					(unit 1)
				)
			)
		)
	)
	(symbol
		(lib_id "antmicropower:+5V")
		(at 91.44 123.19 0)
		(unit 1)
		(exclude_from_sim no)
		(in_bom yes)
		(on_board yes)
		(dnp no)
		(property "Reference" "#PWR0395"
			(at 91.44 127 0)
			(effects
				(font
					(size 1.27 1.27)
				)
				(justify left bottom)
				(hide yes)
			)
		)
		(property "Value" "+12V"
			(at 89.535 120.015 0)
			(effects
				(font
					(size 1.27 1.27)
					(thickness 0.15)
				)
				(justify left bottom)
			)
		)
		(property "Footprint" ""
			(at 106.68 130.81 0)
			(effects
				(font
					(size 1.27 1.27)
					(thickness 0.15)
				)
				(justify left bottom)
				(hide yes)
			)
		)
		(property "Datasheet" ""
			(at 106.68 133.35 0)
			(effects
				(font
					(size 1.27 1.27)
					(thickness 0.15)
				)
				(justify left bottom)
				(hide yes)
			)
		)
		(property "Description" ""
			(at 91.44 123.19 0)
			(effects
				(font
					(size 1.27 1.27)
				)
				(hide yes)
			)
		)
		(property "Author" "Antmicro"
			(at 106.68 130.81 0)
			(effects
				(font
					(size 1.27 1.27)
					(thickness 0.15)
				)
				(justify left bottom)
				(hide yes)
			)
		)
		(property "License" "Apache-2.0"
			(at 106.68 133.35 0)
			(effects
				(font
					(size 1.27 1.27)
					(thickness 0.15)
				)
				(justify left bottom)
				(hide yes)
			)
		)
		(pin "1"
		)
		(instances
			(project "jetson-agx-thor-baseboard"
				(path ""
					(reference "#PWR0395")
					(unit 1)
				)
			)
		)
	)
	(symbol
		(lib_id "antmicropower:+3V3_AON")
		(at 218.44 137.16 0)
		(mirror y)
		(unit 1)
		(exclude_from_sim no)
		(in_bom yes)
		(on_board yes)
		(dnp no)
		(property "Reference" "#PWR0406"
			(at 218.44 140.97 0)
			(effects
				(font
					(size 1.27 1.27)
				)
				(hide yes)
			)
		)
		(property "Value" "+3V3_AON"
			(at 223.774 132.588 0)
			(effects
				(font
					(size 1.27 1.27)
				)
				(justify left)
			)
		)
		(property "Footprint" ""
			(at 218.44 137.16 0)
			(effects
				(font
					(size 1.27 1.27)
				)
				(hide yes)
			)
		)
		(property "Datasheet" ""
			(at 218.44 137.16 0)
			(effects
				(font
					(size 1.27 1.27)
				)
				(hide yes)
			)
		)
		(property "Description" ""
			(at 218.44 137.16 0)
			(effects
				(font
					(size 1.27 1.27)
				)
				(hide yes)
			)
		)
		(pin "1"
		)
		(instances
			(project "jetson-agx-thor-baseboard"
				(path ""
					(reference "#PWR0406")
					(unit 1)
				)
			)
		)
	)
	(symbol
		(lib_id "antmicroInterfaceIOExpanders:PCAL6408A_VQFN")
		(at 302.26 129.54 0)
		(unit 1)
		(exclude_from_sim no)
		(in_bom yes)
		(on_board yes)
		(dnp no)
		(property "Reference" "U71"
			(at 312.42 123.19 0)
			(effects
				(font
					(size 1.27 1.27)
				)
			)
		)
		(property "Value" "PCAL6408A_VQFN"
			(at 337.82 137.16 0)
			(effects
				(font
					(size 1.27 1.27)
					(thickness 0.15)
				)
				(justify left bottom)
				(hide yes)
			)
		)
		(property "Footprint" "antmicro-footprints:VQFN-16-1EP_3x3mm_P0.5mm_EP1.68x1.68mm"
			(at 337.82 139.7 0)
			(effects
				(font
					(size 1.27 1.27)
					(thickness 0.15)
				)
				(justify left bottom)
				(hide yes)
			)
		)
		(property "Datasheet" "https://eu.mouser.com/datasheet/2/302/PCAL6408A-3139197.pdf"
			(at 337.82 142.24 0)
			(effects
				(font
					(size 1.27 1.27)
					(thickness 0.15)
				)
				(justify left bottom)
				(hide yes)
			)
		)
		(property "Description" "I/O Expander, 8 bit, I2C, 1.65-5.5 V, HVQFN, 16 Pins"
			(at 302.26 129.54 0)
			(effects
				(font
					(size 1.27 1.27)
				)
				(hide yes)
			)
		)
		(property "MPN" "PCAL6408ABSHP"
			(at 312.42 125.73 0)
			(effects
				(font
					(size 1.27 1.27)
					(thickness 0.15)
				)
			)
		)
		(property "Manufacturer" "NXP"
			(at 337.82 144.78 0)
			(effects
				(font
					(size 1.27 1.27)
					(thickness 0.15)
				)
				(justify left bottom)
				(hide yes)
			)
		)
		(property "Author" "Antmicro"
			(at 337.82 147.32 0)
			(effects
				(font
					(size 1.27 1.27)
					(thickness 0.15)
				)
				(justify left bottom)
				(hide yes)
			)
		)
		(property "License" "Apache-2.0"
			(at 337.82 149.86 0)
			(effects
				(font
					(size 1.27 1.27)
					(thickness 0.15)
				)
				(justify left bottom)
				(hide yes)
			)
		)
		(pin "1"
		)
		(pin "10"
		)
		(pin "11"
		)
		(pin "12"
		)
		(pin "13"
		)
		(pin "14"
		)
		(pin "15"
		)
		(pin "16"
		)
		(pin "17"
		)
		(pin "2"
		)
		(pin "3"
		)
		(pin "4"
		)
		(pin "5"
		)
		(pin "6"
		)
		(pin "7"
		)
		(pin "8"
		)
		(pin "9"
		)
		(instances
			(project "jetson-agx-thor-baseboard"
				(path ""
					(reference "U71")
					(unit 1)
				)
			)
		)
	)
	(symbol
		(lib_id "antmicropower:GND")
		(at 212.09 59.69 0)
		(unit 1)
		(exclude_from_sim no)
		(in_bom yes)
		(on_board yes)
		(dnp no)
		(fields_autoplaced yes)
		(property "Reference" "#PWR0410"
			(at 212.09 66.04 0)
			(effects
				(font
					(size 1.27 1.27)
				)
				(justify left bottom)
				(hide yes)
			)
		)
		(property "Value" "GND"
			(at 212.09 63.5 0)
			(effects
				(font
					(size 1.27 1.27)
					(thickness 0.15)
				)
			)
		)
		(property "Footprint" ""
			(at 220.98 67.31 0)
			(effects
				(font
					(size 1.27 1.27)
					(thickness 0.15)
				)
				(justify left bottom)
				(hide yes)
			)
		)
		(property "Datasheet" ""
			(at 220.98 72.39 0)
			(effects
				(font
					(size 1.27 1.27)
					(thickness 0.15)
				)
				(justify left bottom)
				(hide yes)
			)
		)
		(property "Description" ""
			(at 212.09 59.69 0)
			(effects
				(font
					(size 1.27 1.27)
				)
				(hide yes)
			)
		)
		(property "Author" "Antmicro"
			(at 220.98 67.31 0)
			(effects
				(font
					(size 1.27 1.27)
					(thickness 0.15)
				)
				(justify left bottom)
				(hide yes)
			)
		)
		(property "License" "Apache-2.0"
			(at 220.98 69.85 0)
			(effects
				(font
					(size 1.27 1.27)
					(thickness 0.15)
				)
				(justify left bottom)
				(hide yes)
			)
		)
		(pin "1"
		)
		(instances
			(project "jetson-agx-thor-baseboard"
				(path ""
					(reference "#PWR0410")
					(unit 1)
				)
			)
		)
	)
	(symbol
		(lib_id "antmicroTransistorsFETsMOSFETsSingle:DMG1012T-7")
		(at 50.8 74.93 0)
		(unit 1)
		(exclude_from_sim no)
		(in_bom yes)
		(on_board yes)
		(dnp no)
		(property "Reference" "Q1"
			(at 52.324 68.834 0)
			(effects
				(font
					(size 1.27 1.27)
					(thickness 0.15)
				)
				(justify right)
			)
		)
		(property "Value" "DMG1012T-7"
			(at 73.66 83.82 0)
			(effects
				(font
					(size 1.27 1.27)
					(thickness 0.15)
				)
				(justify left bottom)
				(hide yes)
			)
		)
		(property "Footprint" "antmicro-footprints:SOT-523"
			(at 73.66 86.36 0)
			(effects
				(font
					(size 1.27 1.27)
					(thickness 0.15)
				)
				(justify left bottom)
				(hide yes)
			)
		)
		(property "Datasheet" "https://www.diodes.com/assets/Datasheets/ds31783.pdf"
			(at 73.66 88.9 0)
			(effects
				(font
					(size 1.27 1.27)
					(thickness 0.15)
				)
				(justify left bottom)
				(hide yes)
			)
		)
		(property "Description" "Power MOSFET, N Channel, 20 V, 630 mA, 0.3 ohm, SOT-523, Surface Mount"
			(at 73.66 101.6 0)
			(effects
				(font
					(size 1.27 1.27)
				)
				(justify left bottom)
				(hide yes)
			)
		)
		(property "MPN" "DMG1012T-7"
			(at 52.324 71.374 0)
			(effects
				(font
					(size 1.27 1.27)
					(thickness 0.15)
				)
				(justify right)
			)
		)
		(property "Manufacturer" "Diodes Incorporated"
			(at 73.66 93.98 0)
			(effects
				(font
					(size 1.27 1.27)
					(thickness 0.15)
				)
				(justify left bottom)
				(hide yes)
			)
		)
		(property "Author" "Antmicro"
			(at 73.66 96.52 0)
			(effects
				(font
					(size 1.27 1.27)
					(thickness 0.15)
				)
				(justify left bottom)
				(hide yes)
			)
		)
		(property "License" "Apache-2.0"
			(at 73.66 99.06 0)
			(effects
				(font
					(size 1.27 1.27)
					(thickness 0.15)
				)
				(justify left bottom)
				(hide yes)
			)
		)
		(pin "3"
		)
		(pin "1"
		)
		(pin "2"
		)
		(instances
			(project "jetson-agx-thor-baseboard"
				(path ""
					(reference "Q1")
					(unit 1)
				)
			)
		)
	)
	(symbol
		(lib_id "antmicroTVSDiodes:ESDA25P35-1U1M")
		(at 95.25 129.54 270)
		(unit 1)
		(exclude_from_sim no)
		(in_bom yes)
		(on_board yes)
		(dnp no)
		(property "Reference" "D64"
			(at 95.25 129.794 90)
			(effects
				(font
					(size 1.27 1.27)
					(thickness 0.15)
				)
				(justify left)
			)
		)
		(property "Value" "ESDA25P35-1U1M"
			(at 80.01 153.67 0)
			(effects
				(font
					(size 1.27 1.27)
					(thickness 0.15)
				)
				(justify left bottom)
				(hide yes)
			)
		)
		(property "Footprint" "antmicro-footprints:QFN-2L_1.6x1x0.55mm"
			(at 85.09 153.67 0)
			(effects
				(font
					(size 1.27 1.27)
					(thickness 0.15)
				)
				(justify left bottom)
				(hide yes)
			)
		)
		(property "Datasheet" "https://www.st.com/resource/en/datasheet/esda25p35-1u1m.pdf"
			(at 82.55 153.67 0)
			(effects
				(font
					(size 1.27 1.27)
					(thickness 0.15)
				)
				(justify left bottom)
				(hide yes)
			)
		)
		(property "Description" "Unidirectional TVS, 30 kV, QFN-2L, 22 V, 195 pF"
			(at 69.85 153.67 0)
			(effects
				(font
					(size 1.27 1.27)
				)
				(justify left bottom)
				(hide yes)
			)
		)
		(property "MPN" "ESDA25P35-1U1M"
			(at 95.504 134.112 90)
			(effects
				(font
					(size 1.27 1.27)
					(thickness 0.15)
				)
				(justify left)
			)
		)
		(property "Manufacturer" "STMicroelectronics"
			(at 77.47 153.67 0)
			(effects
				(font
					(size 1.27 1.27)
					(thickness 0.15)
				)
				(justify left bottom)
				(hide yes)
			)
		)
		(property "Author" "Antmicro"
			(at 74.93 153.67 0)
			(effects
				(font
					(size 1.27 1.27)
					(thickness 0.15)
				)
				(justify left bottom)
				(hide yes)
			)
		)
		(property "License" "Apache-2.0"
			(at 72.39 153.67 0)
			(effects
				(font
					(size 1.27 1.27)
					(thickness 0.15)
				)
				(justify left bottom)
				(hide yes)
			)
		)
		(pin "2"
		)
		(pin "1"
		)
		(instances
			(project ""
				(path ""
					(reference "D64")
					(unit 1)
				)
			)
		)
	)
	(symbol
		(lib_id "antmicropower:+3V3")
		(at 57.15 58.42 0)
		(unit 1)
		(exclude_from_sim no)
		(in_bom yes)
		(on_board yes)
		(dnp no)
		(property "Reference" "#PWR0560"
			(at 72.39 58.42 0)
			(effects
				(font
					(size 1.27 1.27)
					(thickness 0.15)
				)
				(justify left bottom)
				(hide yes)
			)
		)
		(property "Value" "+3V3"
			(at 57.15 54.864 0)
			(effects
				(font
					(size 1.27 1.27)
					(thickness 0.15)
				)
			)
		)
		(property "Footprint" ""
			(at 72.39 66.04 0)
			(effects
				(font
					(size 1.27 1.27)
					(thickness 0.15)
				)
				(justify left bottom)
				(hide yes)
			)
		)
		(property "Datasheet" ""
			(at 72.39 68.58 0)
			(effects
				(font
					(size 1.27 1.27)
					(thickness 0.15)
				)
				(justify left bottom)
				(hide yes)
			)
		)
		(property "Description" ""
			(at 57.15 58.42 0)
			(effects
				(font
					(size 1.27 1.27)
				)
				(hide yes)
			)
		)
		(property "Author" "Antmicro"
			(at 72.39 60.96 0)
			(effects
				(font
					(size 1.27 1.27)
					(thickness 0.15)
				)
				(justify left bottom)
				(hide yes)
			)
		)
		(property "License" "Apache-2.0"
			(at 72.39 63.5 0)
			(effects
				(font
					(size 1.27 1.27)
					(thickness 0.15)
				)
				(justify left bottom)
				(hide yes)
			)
		)
		(pin "1"
		)
		(instances
			(project "jetson-agx-thor-baseboard"
				(path ""
					(reference "#PWR0560")
					(unit 1)
				)
			)
		)
	)
	(symbol
		(lib_id "antmicroPMICPowerDistributionSwitchesLoadDrivers:AP22615A_TSOT26")
		(at 284.48 49.53 0)
		(unit 1)
		(exclude_from_sim no)
		(in_bom yes)
		(on_board yes)
		(dnp no)
		(property "Reference" "U55"
			(at 292.1 43.18 0)
			(effects
				(font
					(size 1.27 1.27)
				)
			)
		)
		(property "Value" "AP22615A_TSOT26"
			(at 314.96 54.61 0)
			(effects
				(font
					(size 1.27 1.27)
					(thickness 0.15)
				)
				(justify left bottom)
				(hide yes)
			)
		)
		(property "Footprint" "antmicro-footprints:TSOT23-6"
			(at 314.96 57.15 0)
			(effects
				(font
					(size 1.27 1.27)
					(thickness 0.15)
				)
				(justify left bottom)
				(hide yes)
			)
		)
		(property "Datasheet" "https://www.mouser.com/datasheet/2/115/DIOD_S_A0008958405_1-2543193.pdf"
			(at 314.96 59.69 0)
			(effects
				(font
					(size 1.27 1.27)
					(thickness 0.15)
				)
				(justify left bottom)
				(hide yes)
			)
		)
		(property "Description" "Power Load Distribution Switch, High Side, Active High, 1 Output, 5.5 V, 3.6 A, 0.04 ohm, TSOT-26-6"
			(at 284.48 49.53 0)
			(effects
				(font
					(size 1.27 1.27)
				)
				(hide yes)
			)
		)
		(property "MPN" "AP22615AWU-7"
			(at 292.1 45.72 0)
			(effects
				(font
					(size 1.27 1.27)
					(thickness 0.15)
				)
			)
		)
		(property "Manufacturer" "Diodes Incorporated"
			(at 314.96 64.77 0)
			(effects
				(font
					(size 1.27 1.27)
					(thickness 0.15)
				)
				(justify left bottom)
				(hide yes)
			)
		)
		(property "Author" "Antmicro"
			(at 314.96 67.31 0)
			(effects
				(font
					(size 1.27 1.27)
					(thickness 0.15)
				)
				(justify left bottom)
				(hide yes)
			)
		)
		(property "License" "Apache-2.0"
			(at 314.96 69.85 0)
			(effects
				(font
					(size 1.27 1.27)
					(thickness 0.15)
				)
				(justify left bottom)
				(hide yes)
			)
		)
		(pin "1"
		)
		(pin "2"
		)
		(pin "3"
		)
		(pin "4"
		)
		(pin "5"
		)
		(pin "6"
		)
		(instances
			(project "jetson-agx-thor-baseboard"
				(path ""
					(reference "U55")
					(unit 1)
				)
			)
		)
	)
	(symbol
		(lib_id "antmicroLEDIndicationDiscrete:LED_G_0603_LTST-C190GKT")
		(at 53.34 214.63 90)
		(unit 1)
		(exclude_from_sim no)
		(in_bom yes)
		(on_board yes)
		(dnp no)
		(property "Reference" "D35"
			(at 54.61 210.82 90)
			(effects
				(font
					(size 1.27 1.27)
				)
				(justify right)
			)
		)
		(property "Value" "LED_G_0603_LTST-C190GKT"
			(at 60.96 191.77 0)
			(effects
				(font
					(size 1.27 1.27)
					(thickness 0.15)
				)
				(justify left bottom)
				(hide yes)
			)
		)
		(property "Footprint" "antmicro-footprints:LED_0603_1608Metric_G"
			(at 63.5 191.77 0)
			(effects
				(font
					(size 1.27 1.27)
					(thickness 0.15)
				)
				(justify left bottom)
				(hide yes)
			)
		)
		(property "Datasheet" "https://media.digikey.com/pdf/Data%20Sheets/Lite-On%20PDFs/LTST-C190GKT.pdf"
			(at 66.04 191.77 0)
			(effects
				(font
					(size 1.27 1.27)
					(thickness 0.15)
				)
				(justify left bottom)
				(hide yes)
			)
		)
		(property "Description" "LED, Green, SMD, 0603, 20 mA, 2.1 V, 569 nm"
			(at 53.34 214.63 0)
			(effects
				(font
					(size 1.27 1.27)
				)
				(hide yes)
			)
		)
		(property "MPN" "LTST-C190GKT"
			(at 68.58 191.77 0)
			(effects
				(font
					(size 1.27 1.27)
					(thickness 0.15)
				)
				(justify left bottom)
				(hide yes)
			)
		)
		(property "Manufacturer" "Lite-On"
			(at 71.12 191.77 0)
			(effects
				(font
					(size 1.27 1.27)
					(thickness 0.15)
				)
				(justify left bottom)
				(hide yes)
			)
		)
		(property "Author" "Antmicro"
			(at 73.66 191.77 0)
			(effects
				(font
					(size 1.27 1.27)
					(thickness 0.15)
				)
				(justify left bottom)
				(hide yes)
			)
		)
		(property "License" "Apache-2.0"
			(at 76.2 191.77 0)
			(effects
				(font
					(size 1.27 1.27)
					(thickness 0.15)
				)
				(justify left bottom)
				(hide yes)
			)
		)
		(property "Color" "Green"
			(at 54.61 213.36 90)
			(effects
				(font
					(size 1.27 1.27)
				)
				(justify right)
			)
		)
		(pin "1"
		)
		(pin "2"
		)
		(instances
			(project "jetson-agx-thor-baseboard"
				(path ""
					(reference "D35")
					(unit 1)
				)
			)
		)
	)
	(symbol
		(lib_id "antmicroResistors0402:R_0R_0402")
		(at 300.99 156.21 90)
		(unit 1)
		(exclude_from_sim no)
		(in_bom yes)
		(on_board yes)
		(dnp no)
		(property "Reference" "R345"
			(at 294.386 152.4 90)
			(effects
				(font
					(size 1.27 1.27)
				)
				(justify right)
			)
		)
		(property "Value" "R_0R_0402"
			(at 313.69 135.89 0)
			(effects
				(font
					(size 1.27 1.27)
					(thickness 0.15)
				)
				(justify left bottom)
				(hide yes)
			)
		)
		(property "Footprint" "antmicro-footprints:R_0402_1005Metric"
			(at 316.23 135.89 0)
			(effects
				(font
					(size 1.27 1.27)
					(thickness 0.15)
				)
				(justify left bottom)
				(hide yes)
			)
		)
		(property "Datasheet" "https://industrial.panasonic.com/cdbs/www-data/pdf/RDA0000/AOA0000C301.pdf"
			(at 318.77 135.89 0)
			(effects
				(font
					(size 1.27 1.27)
					(thickness 0.15)
				)
				(justify left bottom)
				(hide yes)
			)
		)
		(property "Description" "SMD Chip Resistor, Jumper, 0 ohm, 100 mW, 0402 [1005 Metric], Thick Film, General Purpose"
			(at 300.99 156.21 0)
			(effects
				(font
					(size 1.27 1.27)
				)
				(hide yes)
			)
		)
		(property "Manufacturer" "Panasonic"
			(at 323.85 135.89 0)
			(effects
				(font
					(size 1.27 1.27)
					(thickness 0.15)
				)
				(justify left bottom)
				(hide yes)
			)
		)
		(property "MPN" "ERJ2GE0R00X"
			(at 321.31 135.89 0)
			(effects
				(font
					(size 1.27 1.27)
					(thickness 0.15)
				)
				(justify left bottom)
				(hide yes)
			)
		)
		(property "Val" "0R"
			(at 296.672 154.432 90)
			(effects
				(font
					(size 1.27 1.27)
					(thickness 0.15)
				)
				(justify right)
			)
		)
		(property "License" "Apache-2.0"
			(at 326.39 135.89 0)
			(effects
				(font
					(size 1.27 1.27)
					(thickness 0.15)
				)
				(justify left bottom)
				(hide yes)
			)
		)
		(property "Author" "Antmicro"
			(at 328.93 135.89 0)
			(effects
				(font
					(size 1.27 1.27)
					(thickness 0.15)
				)
				(justify left bottom)
				(hide yes)
			)
		)
		(property "Tolerance" "~"
			(at 311.15 135.89 0)
			(effects
				(font
					(size 1.27 1.27)
				)
				(justify left bottom)
				(hide yes)
			)
		)
		(property "Current" "1A"
			(at 331.47 135.89 0)
			(effects
				(font
					(size 1.27 1.27)
					(thickness 0.15)
				)
				(justify left bottom)
				(hide yes)
			)
		)
		(pin "1"
		)
		(pin "2"
		)
		(instances
			(project "jetson-agx-thor-baseboard"
				(path ""
					(reference "R345")
					(unit 1)
				)
			)
		)
	)
	(symbol
		(lib_id "antmicroCapacitors0402:C_100n_0402")
		(at 76.2 36.83 90)
		(unit 1)
		(exclude_from_sim no)
		(in_bom yes)
		(on_board yes)
		(dnp no)
		(property "Reference" "C203"
			(at 77.978 33.02 90)
			(effects
				(font
					(size 1.27 1.27)
					(thickness 0.15)
				)
				(justify right)
			)
		)
		(property "Value" "C_100n_0402"
			(at 99.06 21.59 0)
			(effects
				(font
					(size 1.27 1.27)
					(thickness 0.15)
				)
				(justify left bottom)
				(hide yes)
			)
		)
		(property "Footprint" "antmicro-footprints:C_0402_1005Metric"
			(at 101.6 21.59 0)
			(effects
				(font
					(size 1.27 1.27)
					(thickness 0.15)
				)
				(justify left bottom)
				(hide yes)
			)
		)
		(property "Datasheet" "https://www.murata.com/products/productdetail?partno=GRM155R61H104KE14%23"
			(at 104.14 21.59 0)
			(effects
				(font
					(size 1.27 1.27)
					(thickness 0.15)
				)
				(justify left bottom)
				(hide yes)
			)
		)
		(property "Description" "SMD Multilayer Ceramic Capacitor, 0.1 µF, 50 V, 0402 [1005 Metric], ± 10%, X5R, GRM Series"
			(at 76.2 36.83 0)
			(effects
				(font
					(size 1.27 1.27)
				)
				(hide yes)
			)
		)
		(property "MPN" "GRM155R61H104KE14D"
			(at 106.68 21.59 0)
			(effects
				(font
					(size 1.27 1.27)
					(thickness 0.15)
				)
				(justify left bottom)
				(hide yes)
			)
		)
		(property "Val" "100n"
			(at 77.978 35.56 90)
			(effects
				(font
					(size 1.27 1.27)
					(thickness 0.15)
				)
				(justify right)
			)
		)
		(property "Voltage" "50V"
			(at 86.36 21.59 0)
			(effects
				(font
					(size 1.27 1.27)
					(thickness 0.15)
				)
				(justify left bottom)
				(hide yes)
			)
		)
		(property "Dielectric" "X5R"
			(at 88.9 21.59 0)
			(effects
				(font
					(size 1.27 1.27)
					(thickness 0.15)
				)
				(justify left bottom)
				(hide yes)
			)
		)
		(property "Manufacturer" "Murata"
			(at 91.44 21.59 0)
			(effects
				(font
					(size 1.27 1.27)
					(thickness 0.15)
				)
				(justify left bottom)
				(hide yes)
			)
		)
		(property "License" "Apache-2.0"
			(at 93.98 21.59 0)
			(effects
				(font
					(size 1.27 1.27)
					(thickness 0.15)
				)
				(justify left bottom)
				(hide yes)
			)
		)
		(property "Author" "Antmicro"
			(at 96.52 21.59 0)
			(effects
				(font
					(size 1.27 1.27)
					(thickness 0.15)
				)
				(justify left bottom)
				(hide yes)
			)
		)
		(pin "1"
		)
		(pin "2"
		)
		(instances
			(project "jetson-agx-thor-baseboard"
				(path ""
					(reference "C203")
					(unit 1)
				)
			)
		)
	)
	(symbol
		(lib_id "antmicroResistors0402:R_10k_0402")
		(at 306.07 58.42 90)
		(unit 1)
		(exclude_from_sim no)
		(in_bom yes)
		(on_board yes)
		(dnp no)
		(property "Reference" "R245"
			(at 307.34 54.61 90)
			(effects
				(font
					(size 1.27 1.27)
				)
				(justify right)
			)
		)
		(property "Value" "R_10k_0402"
			(at 318.77 38.1 0)
			(effects
				(font
					(size 1.27 1.27)
					(thickness 0.15)
				)
				(justify left bottom)
				(hide yes)
			)
		)
		(property "Footprint" "antmicro-footprints:R_0402_1005Metric"
			(at 321.31 38.1 0)
			(effects
				(font
					(size 1.27 1.27)
					(thickness 0.15)
				)
				(justify left bottom)
				(hide yes)
			)
		)
		(property "Datasheet" "https://www.bourns.com/docs/product-datasheets/cr.pdf"
			(at 323.85 38.1 0)
			(effects
				(font
					(size 1.27 1.27)
					(thickness 0.15)
				)
				(justify left bottom)
				(hide yes)
			)
		)
		(property "Description" "SMD Chip Resistor, 10 kohm, ± 1%, 62.5 mW, 0402 [1005 Metric], Thick Film, General Purpose"
			(at 306.07 58.42 0)
			(effects
				(font
					(size 1.27 1.27)
				)
				(hide yes)
			)
		)
		(property "Manufacturer" "Bourns"
			(at 328.93 38.1 0)
			(effects
				(font
					(size 1.27 1.27)
					(thickness 0.15)
				)
				(justify left bottom)
				(hide yes)
			)
		)
		(property "MPN" "CR0402-FX-1002GLF"
			(at 326.39 38.1 0)
			(effects
				(font
					(size 1.27 1.27)
					(thickness 0.15)
				)
				(justify left bottom)
				(hide yes)
			)
		)
		(property "Val" "10k"
			(at 307.34 57.15 90)
			(effects
				(font
					(size 1.27 1.27)
					(thickness 0.15)
				)
				(justify right)
			)
		)
		(property "License" "Apache-2.0"
			(at 331.47 38.1 0)
			(effects
				(font
					(size 1.27 1.27)
					(thickness 0.15)
				)
				(justify left bottom)
				(hide yes)
			)
		)
		(property "Author" "Antmicro"
			(at 334.01 38.1 0)
			(effects
				(font
					(size 1.27 1.27)
					(thickness 0.15)
				)
				(justify left bottom)
				(hide yes)
			)
		)
		(property "Tolerance" "1%"
			(at 316.23 38.1 0)
			(effects
				(font
					(size 1.27 1.27)
				)
				(justify left bottom)
				(hide yes)
			)
		)
		(pin "1"
		)
		(pin "2"
		)
		(instances
			(project "jetson-agx-thor-baseboard"
				(path ""
					(reference "R245")
					(unit 1)
				)
			)
		)
	)
	(symbol
		(lib_id "antmicropower:+3V3")
		(at 102.87 201.93 0)
		(unit 1)
		(exclude_from_sim no)
		(in_bom yes)
		(on_board yes)
		(dnp no)
		(property "Reference" "#PWR0399"
			(at 102.87 205.74 0)
			(effects
				(font
					(size 1.27 1.27)
				)
				(justify left bottom)
				(hide yes)
			)
		)
		(property "Value" "+3V3"
			(at 99.695 198.12 0)
			(effects
				(font
					(size 1.27 1.27)
					(thickness 0.15)
				)
				(justify left)
			)
		)
		(property "Footprint" ""
			(at 118.11 209.55 0)
			(effects
				(font
					(size 1.27 1.27)
					(thickness 0.15)
				)
				(justify left bottom)
				(hide yes)
			)
		)
		(property "Datasheet" ""
			(at 118.11 212.09 0)
			(effects
				(font
					(size 1.27 1.27)
					(thickness 0.15)
				)
				(justify left bottom)
				(hide yes)
			)
		)
		(property "Description" ""
			(at 102.87 201.93 0)
			(effects
				(font
					(size 1.27 1.27)
				)
				(hide yes)
			)
		)
		(property "Author" "Antmicro"
			(at 118.11 204.47 0)
			(effects
				(font
					(size 1.27 1.27)
					(thickness 0.15)
				)
				(justify left bottom)
				(hide yes)
			)
		)
		(property "License" "Apache-2.0"
			(at 118.11 207.01 0)
			(effects
				(font
					(size 1.27 1.27)
					(thickness 0.15)
				)
				(justify left bottom)
				(hide yes)
			)
		)
		(pin "1"
		)
		(instances
			(project "jetson-agx-thor-baseboard"
				(path ""
					(reference "#PWR0399")
					(unit 1)
				)
			)
		)
	)
	(symbol
		(lib_id "antmicroResistors0402:R_0R_0402")
		(at 96.52 127 0)
		(unit 1)
		(exclude_from_sim no)
		(in_bom yes)
		(on_board yes)
		(dnp no)
		(property "Reference" "R28"
			(at 101.6 126.365 0)
			(effects
				(font
					(size 1.27 1.27)
				)
				(justify left bottom)
			)
		)
		(property "Value" "R_0R_0402"
			(at 116.84 139.7 0)
			(effects
				(font
					(size 1.27 1.27)
					(thickness 0.15)
				)
				(justify left bottom)
				(hide yes)
			)
		)
		(property "Footprint" "antmicro-footprints:R_0402_1005Metric"
			(at 116.84 142.24 0)
			(effects
				(font
					(size 1.27 1.27)
					(thickness 0.15)
				)
				(justify left bottom)
				(hide yes)
			)
		)
		(property "Datasheet" "https://industrial.panasonic.com/cdbs/www-data/pdf/RDA0000/AOA0000C301.pdf"
			(at 116.84 144.78 0)
			(effects
				(font
					(size 1.27 1.27)
					(thickness 0.15)
				)
				(justify left bottom)
				(hide yes)
			)
		)
		(property "Description" "SMD Chip Resistor, Jumper, 0 ohm, 100 mW, 0402 [1005 Metric], Thick Film, General Purpose"
			(at 96.52 127 0)
			(effects
				(font
					(size 1.27 1.27)
				)
				(hide yes)
			)
		)
		(property "Manufacturer" "Panasonic"
			(at 116.84 149.86 0)
			(effects
				(font
					(size 1.27 1.27)
					(thickness 0.15)
				)
				(justify left bottom)
				(hide yes)
			)
		)
		(property "MPN" "ERJ2GE0R00X"
			(at 116.84 147.32 0)
			(effects
				(font
					(size 1.27 1.27)
					(thickness 0.15)
				)
				(justify left bottom)
				(hide yes)
			)
		)
		(property "Val" "0R"
			(at 93.98 126.365 0)
			(effects
				(font
					(size 1.27 1.27)
					(thickness 0.15)
				)
				(justify left bottom)
			)
		)
		(property "License" "Apache-2.0"
			(at 116.84 152.4 0)
			(effects
				(font
					(size 1.27 1.27)
					(thickness 0.15)
				)
				(justify left bottom)
				(hide yes)
			)
		)
		(property "Author" "Antmicro"
			(at 116.84 154.94 0)
			(effects
				(font
					(size 1.27 1.27)
					(thickness 0.15)
				)
				(justify left bottom)
				(hide yes)
			)
		)
		(property "Tolerance" "~"
			(at 116.84 137.16 0)
			(effects
				(font
					(size 1.27 1.27)
				)
				(justify left bottom)
				(hide yes)
			)
		)
		(property "Current" "1A"
			(at 116.84 157.48 0)
			(effects
				(font
					(size 1.27 1.27)
					(thickness 0.15)
				)
				(justify left bottom)
				(hide yes)
			)
		)
		(pin "1"
		)
		(pin "2"
		)
		(instances
			(project "jetson-agx-thor-baseboard"
				(path ""
					(reference "R28")
					(unit 1)
				)
			)
		)
	)
	(symbol
		(lib_id "antmicroResistors0402:R_10k_0402")
		(at 274.32 44.45 90)
		(unit 1)
		(exclude_from_sim no)
		(in_bom yes)
		(on_board yes)
		(dnp no)
		(property "Reference" "R243"
			(at 275.59 40.64 90)
			(effects
				(font
					(size 1.27 1.27)
				)
				(justify right)
			)
		)
		(property "Value" "R_10k_0402"
			(at 287.02 24.13 0)
			(effects
				(font
					(size 1.27 1.27)
					(thickness 0.15)
				)
				(justify left bottom)
				(hide yes)
			)
		)
		(property "Footprint" "antmicro-footprints:R_0402_1005Metric"
			(at 289.56 24.13 0)
			(effects
				(font
					(size 1.27 1.27)
					(thickness 0.15)
				)
				(justify left bottom)
				(hide yes)
			)
		)
		(property "Datasheet" "https://www.bourns.com/docs/product-datasheets/cr.pdf"
			(at 292.1 24.13 0)
			(effects
				(font
					(size 1.27 1.27)
					(thickness 0.15)
				)
				(justify left bottom)
				(hide yes)
			)
		)
		(property "Description" "SMD Chip Resistor, 10 kohm, ± 1%, 62.5 mW, 0402 [1005 Metric], Thick Film, General Purpose"
			(at 274.32 44.45 0)
			(effects
				(font
					(size 1.27 1.27)
				)
				(hide yes)
			)
		)
		(property "Manufacturer" "Bourns"
			(at 297.18 24.13 0)
			(effects
				(font
					(size 1.27 1.27)
					(thickness 0.15)
				)
				(justify left bottom)
				(hide yes)
			)
		)
		(property "MPN" "CR0402-FX-1002GLF"
			(at 294.64 24.13 0)
			(effects
				(font
					(size 1.27 1.27)
					(thickness 0.15)
				)
				(justify left bottom)
				(hide yes)
			)
		)
		(property "Val" "10k"
			(at 275.59 43.18 90)
			(effects
				(font
					(size 1.27 1.27)
					(thickness 0.15)
				)
				(justify right)
			)
		)
		(property "License" "Apache-2.0"
			(at 299.72 24.13 0)
			(effects
				(font
					(size 1.27 1.27)
					(thickness 0.15)
				)
				(justify left bottom)
				(hide yes)
			)
		)
		(property "Author" "Antmicro"
			(at 302.26 24.13 0)
			(effects
				(font
					(size 1.27 1.27)
					(thickness 0.15)
				)
				(justify left bottom)
				(hide yes)
			)
		)
		(property "Tolerance" "1%"
			(at 284.48 24.13 0)
			(effects
				(font
					(size 1.27 1.27)
				)
				(justify left bottom)
				(hide yes)
			)
		)
		(pin "1"
		)
		(pin "2"
		)
		(instances
			(project "jetson-agx-thor-baseboard"
				(path ""
					(reference "R243")
					(unit 1)
				)
			)
		)
	)
	(symbol
		(lib_id "antmicroResistors0402:R_200R_0402")
		(at 227.33 58.42 270)
		(mirror x)
		(unit 1)
		(exclude_from_sim no)
		(in_bom yes)
		(on_board yes)
		(dnp no)
		(property "Reference" "R242"
			(at 228.6 54.61 90)
			(effects
				(font
					(size 1.27 1.27)
				)
				(justify left)
			)
		)
		(property "Value" "R_200R_0402"
			(at 214.63 38.1 0)
			(effects
				(font
					(size 1.27 1.27)
					(thickness 0.15)
				)
				(justify left bottom)
				(hide yes)
			)
		)
		(property "Footprint" "antmicro-footprints:R_0402_1005Metric"
			(at 212.09 38.1 0)
			(effects
				(font
					(size 1.27 1.27)
					(thickness 0.15)
				)
				(justify left bottom)
				(hide yes)
			)
		)
		(property "Datasheet" "https://www.bourns.com/docs/product-datasheets/cr.pdf"
			(at 209.55 38.1 0)
			(effects
				(font
					(size 1.27 1.27)
					(thickness 0.15)
				)
				(justify left bottom)
				(hide yes)
			)
		)
		(property "Description" "SMD Chip Resistor, 200 ohm, ± 1%, 62.5 mW, 0402 [1005 Metric], Thick Film, General Purpose"
			(at 227.33 58.42 0)
			(effects
				(font
					(size 1.27 1.27)
				)
				(hide yes)
			)
		)
		(property "Manufacturer" "Bourns"
			(at 204.47 38.1 0)
			(effects
				(font
					(size 1.27 1.27)
					(thickness 0.15)
				)
				(justify left bottom)
				(hide yes)
			)
		)
		(property "MPN" "CR0402-FX-2000GLF"
			(at 207.01 38.1 0)
			(effects
				(font
					(size 1.27 1.27)
					(thickness 0.15)
				)
				(justify left bottom)
				(hide yes)
			)
		)
		(property "Val" "200R"
			(at 228.6 57.15 90)
			(effects
				(font
					(size 1.27 1.27)
					(thickness 0.15)
				)
				(justify left)
			)
		)
		(property "License" "Apache-2.0"
			(at 201.93 38.1 0)
			(effects
				(font
					(size 1.27 1.27)
					(thickness 0.15)
				)
				(justify left bottom)
				(hide yes)
			)
		)
		(property "Author" "Antmicro"
			(at 199.39 38.1 0)
			(effects
				(font
					(size 1.27 1.27)
					(thickness 0.15)
				)
				(justify left bottom)
				(hide yes)
			)
		)
		(property "Tolerance" "1%"
			(at 217.17 38.1 0)
			(effects
				(font
					(size 1.27 1.27)
				)
				(justify left bottom)
				(hide yes)
			)
		)
		(pin "1"
		)
		(pin "2"
		)
		(instances
			(project "jetson-agx-thor-baseboard"
				(path ""
					(reference "R242")
					(unit 1)
				)
			)
		)
	)
	(symbol
		(lib_id "antmicroResistors0402:R_10k_0402")
		(at 204.47 207.01 90)
		(unit 1)
		(exclude_from_sim no)
		(in_bom yes)
		(on_board yes)
		(dnp no)
		(property "Reference" "R237"
			(at 205.74 203.2 90)
			(effects
				(font
					(size 1.27 1.27)
				)
				(justify right)
			)
		)
		(property "Value" "R_10k_0402"
			(at 217.17 186.69 0)
			(effects
				(font
					(size 1.27 1.27)
					(thickness 0.15)
				)
				(justify left bottom)
				(hide yes)
			)
		)
		(property "Footprint" "antmicro-footprints:R_0402_1005Metric"
			(at 219.71 186.69 0)
			(effects
				(font
					(size 1.27 1.27)
					(thickness 0.15)
				)
				(justify left bottom)
				(hide yes)
			)
		)
		(property "Datasheet" "https://www.bourns.com/docs/product-datasheets/cr.pdf"
			(at 222.25 186.69 0)
			(effects
				(font
					(size 1.27 1.27)
					(thickness 0.15)
				)
				(justify left bottom)
				(hide yes)
			)
		)
		(property "Description" "SMD Chip Resistor, 10 kohm, ± 1%, 62.5 mW, 0402 [1005 Metric], Thick Film, General Purpose"
			(at 204.47 207.01 0)
			(effects
				(font
					(size 1.27 1.27)
				)
				(hide yes)
			)
		)
		(property "Manufacturer" "Bourns"
			(at 227.33 186.69 0)
			(effects
				(font
					(size 1.27 1.27)
					(thickness 0.15)
				)
				(justify left bottom)
				(hide yes)
			)
		)
		(property "MPN" "CR0402-FX-1002GLF"
			(at 224.79 186.69 0)
			(effects
				(font
					(size 1.27 1.27)
					(thickness 0.15)
				)
				(justify left bottom)
				(hide yes)
			)
		)
		(property "Val" "10k"
			(at 205.74 205.74 90)
			(effects
				(font
					(size 1.27 1.27)
					(thickness 0.15)
				)
				(justify right)
			)
		)
		(property "License" "Apache-2.0"
			(at 229.87 186.69 0)
			(effects
				(font
					(size 1.27 1.27)
					(thickness 0.15)
				)
				(justify left bottom)
				(hide yes)
			)
		)
		(property "Author" "Antmicro"
			(at 232.41 186.69 0)
			(effects
				(font
					(size 1.27 1.27)
					(thickness 0.15)
				)
				(justify left bottom)
				(hide yes)
			)
		)
		(property "Tolerance" "1%"
			(at 214.63 186.69 0)
			(effects
				(font
					(size 1.27 1.27)
				)
				(justify left bottom)
				(hide yes)
			)
		)
		(pin "1"
		)
		(pin "2"
		)
		(instances
			(project "jetson-agx-thor-baseboard"
				(path ""
					(reference "R237")
					(unit 1)
				)
			)
		)
	)
	(symbol
		(lib_id "antmicropower:GND")
		(at 44.45 231.14 0)
		(unit 1)
		(exclude_from_sim no)
		(in_bom yes)
		(on_board yes)
		(dnp no)
		(fields_autoplaced yes)
		(property "Reference" "#PWR0388"
			(at 44.45 237.49 0)
			(effects
				(font
					(size 1.27 1.27)
				)
				(justify left bottom)
				(hide yes)
			)
		)
		(property "Value" "GND"
			(at 44.45 234.95 0)
			(effects
				(font
					(size 1.27 1.27)
					(thickness 0.15)
				)
			)
		)
		(property "Footprint" ""
			(at 53.34 238.76 0)
			(effects
				(font
					(size 1.27 1.27)
					(thickness 0.15)
				)
				(justify left bottom)
				(hide yes)
			)
		)
		(property "Datasheet" ""
			(at 53.34 243.84 0)
			(effects
				(font
					(size 1.27 1.27)
					(thickness 0.15)
				)
				(justify left bottom)
				(hide yes)
			)
		)
		(property "Description" ""
			(at 44.45 231.14 0)
			(effects
				(font
					(size 1.27 1.27)
				)
				(hide yes)
			)
		)
		(property "Author" "Antmicro"
			(at 53.34 238.76 0)
			(effects
				(font
					(size 1.27 1.27)
					(thickness 0.15)
				)
				(justify left bottom)
				(hide yes)
			)
		)
		(property "License" "Apache-2.0"
			(at 53.34 241.3 0)
			(effects
				(font
					(size 1.27 1.27)
					(thickness 0.15)
				)
				(justify left bottom)
				(hide yes)
			)
		)
		(pin "1"
		)
		(instances
			(project "jetson-agx-thor-baseboard"
				(path ""
					(reference "#PWR0388")
					(unit 1)
				)
			)
		)
	)
	(symbol
		(lib_id "antmicroLogicTranslatorsLevelShifters:NTS0102_XSON")
		(at 46.99 139.7 0)
		(unit 1)
		(exclude_from_sim no)
		(in_bom yes)
		(on_board yes)
		(dnp no)
		(property "Reference" "U51"
			(at 57.15 133.35 0)
			(effects
				(font
					(size 1.27 1.27)
				)
			)
		)
		(property "Value" "NTS0102_XSON"
			(at 82.55 147.32 0)
			(effects
				(font
					(size 1.27 1.27)
					(thickness 0.15)
				)
				(justify left bottom)
				(hide yes)
			)
		)
		(property "Footprint" "antmicro-footprints:XSON-8_1x1.95mm_P0.5mm"
			(at 82.55 149.86 0)
			(effects
				(font
					(size 1.27 1.27)
					(thickness 0.15)
				)
				(justify left bottom)
				(hide yes)
			)
		)
		(property "Datasheet" "http://www.farnell.com/datasheets/1760723.pdf"
			(at 82.55 152.4 0)
			(effects
				(font
					(size 1.27 1.27)
					(thickness 0.15)
				)
				(justify left bottom)
				(hide yes)
			)
		)
		(property "Description" "Transceiver, 1.65 V to 3.6 V, XSON-8"
			(at 46.99 139.7 0)
			(effects
				(font
					(size 1.27 1.27)
				)
				(hide yes)
			)
		)
		(property "MPN" "NTS0102GT"
			(at 57.15 135.89 0)
			(effects
				(font
					(size 1.27 1.27)
					(thickness 0.15)
				)
			)
		)
		(property "Manufacturer" "NXP"
			(at 82.55 154.94 0)
			(effects
				(font
					(size 1.27 1.27)
					(thickness 0.15)
				)
				(justify left bottom)
				(hide yes)
			)
		)
		(property "Author" "Antmicro"
			(at 82.55 157.48 0)
			(effects
				(font
					(size 1.27 1.27)
					(thickness 0.15)
				)
				(justify left bottom)
				(hide yes)
			)
		)
		(property "License" "Apache-2.0"
			(at 82.55 160.02 0)
			(effects
				(font
					(size 1.27 1.27)
					(thickness 0.15)
				)
				(justify left bottom)
				(hide yes)
			)
		)
		(pin "1"
		)
		(pin "2"
		)
		(pin "3"
		)
		(pin "4"
		)
		(pin "5"
		)
		(pin "6"
		)
		(pin "7"
		)
		(pin "8"
		)
		(instances
			(project "jetson-agx-thor-baseboard"
				(path ""
					(reference "U51")
					(unit 1)
				)
			)
		)
	)
	(symbol
		(lib_id "antmicroResistors0402:R_0R_0402")
		(at 96.52 124.46 0)
		(unit 1)
		(exclude_from_sim no)
		(in_bom no)
		(on_board yes)
		(dnp yes)
		(property "Reference" "R25"
			(at 101.6 123.825 0)
			(effects
				(font
					(size 1.27 1.27)
				)
				(justify left bottom)
			)
		)
		(property "Value" "R_0R_0402"
			(at 116.84 137.16 0)
			(effects
				(font
					(size 1.27 1.27)
					(thickness 0.15)
				)
				(justify left bottom)
				(hide yes)
			)
		)
		(property "Footprint" "antmicro-footprints:R_0402_1005Metric"
			(at 116.84 139.7 0)
			(effects
				(font
					(size 1.27 1.27)
					(thickness 0.15)
				)
				(justify left bottom)
				(hide yes)
			)
		)
		(property "Datasheet" "https://industrial.panasonic.com/cdbs/www-data/pdf/RDA0000/AOA0000C301.pdf"
			(at 116.84 142.24 0)
			(effects
				(font
					(size 1.27 1.27)
					(thickness 0.15)
				)
				(justify left bottom)
				(hide yes)
			)
		)
		(property "Description" "SMD Chip Resistor, Jumper, 0 ohm, 100 mW, 0402 [1005 Metric], Thick Film, General Purpose"
			(at 96.52 124.46 0)
			(effects
				(font
					(size 1.27 1.27)
				)
				(hide yes)
			)
		)
		(property "Manufacturer" "Panasonic"
			(at 116.84 147.32 0)
			(effects
				(font
					(size 1.27 1.27)
					(thickness 0.15)
				)
				(justify left bottom)
				(hide yes)
			)
		)
		(property "MPN" "ERJ2GE0R00X"
			(at 116.84 144.78 0)
			(effects
				(font
					(size 1.27 1.27)
					(thickness 0.15)
				)
				(justify left bottom)
				(hide yes)
			)
		)
		(property "Val" "0R"
			(at 93.98 123.825 0)
			(effects
				(font
					(size 1.27 1.27)
					(thickness 0.15)
				)
				(justify left bottom)
			)
		)
		(property "License" "Apache-2.0"
			(at 116.84 149.86 0)
			(effects
				(font
					(size 1.27 1.27)
					(thickness 0.15)
				)
				(justify left bottom)
				(hide yes)
			)
		)
		(property "Author" "Antmicro"
			(at 116.84 152.4 0)
			(effects
				(font
					(size 1.27 1.27)
					(thickness 0.15)
				)
				(justify left bottom)
				(hide yes)
			)
		)
		(property "Tolerance" "~"
			(at 116.84 134.62 0)
			(effects
				(font
					(size 1.27 1.27)
				)
				(justify left bottom)
				(hide yes)
			)
		)
		(property "Current" "1A"
			(at 116.84 154.94 0)
			(effects
				(font
					(size 1.27 1.27)
					(thickness 0.15)
				)
				(justify left bottom)
				(hide yes)
			)
		)
		(pin "1"
		)
		(pin "2"
		)
		(instances
			(project "jetson-agx-thor-baseboard"
				(path ""
					(reference "R25")
					(unit 1)
				)
			)
		)
	)
	(symbol
		(lib_id "antmicroLEDIndicationDiscrete:LED_G_0603_LTST-C190GKT")
		(at 227.33 64.77 270)
		(mirror x)
		(unit 1)
		(exclude_from_sim no)
		(in_bom yes)
		(on_board yes)
		(dnp no)
		(property "Reference" "D41"
			(at 230.505 60.96 90)
			(effects
				(font
					(size 1.27 1.27)
				)
				(justify left)
			)
		)
		(property "Value" "LED_G_0603_LTST-C190GKT"
			(at 219.71 41.91 0)
			(effects
				(font
					(size 1.27 1.27)
					(thickness 0.15)
				)
				(justify left bottom)
				(hide yes)
			)
		)
		(property "Footprint" "antmicro-footprints:LED_0603_1608Metric_G"
			(at 217.17 41.91 0)
			(effects
				(font
					(size 1.27 1.27)
					(thickness 0.15)
				)
				(justify left bottom)
				(hide yes)
			)
		)
		(property "Datasheet" "https://media.digikey.com/pdf/Data%20Sheets/Lite-On%20PDFs/LTST-C190GKT.pdf"
			(at 214.63 41.91 0)
			(effects
				(font
					(size 1.27 1.27)
					(thickness 0.15)
				)
				(justify left bottom)
				(hide yes)
			)
		)
		(property "Description" "LED, Green, SMD, 0603, 20 mA, 2.1 V, 569 nm"
			(at 227.33 64.77 0)
			(effects
				(font
					(size 1.27 1.27)
				)
				(hide yes)
			)
		)
		(property "MPN" "LTST-C190GKT"
			(at 212.09 41.91 0)
			(effects
				(font
					(size 1.27 1.27)
					(thickness 0.15)
				)
				(justify left bottom)
				(hide yes)
			)
		)
		(property "Manufacturer" "Lite-On"
			(at 209.55 41.91 0)
			(effects
				(font
					(size 1.27 1.27)
					(thickness 0.15)
				)
				(justify left bottom)
				(hide yes)
			)
		)
		(property "Author" "Antmicro"
			(at 207.01 41.91 0)
			(effects
				(font
					(size 1.27 1.27)
					(thickness 0.15)
				)
				(justify left bottom)
				(hide yes)
			)
		)
		(property "License" "Apache-2.0"
			(at 204.47 41.91 0)
			(effects
				(font
					(size 1.27 1.27)
					(thickness 0.15)
				)
				(justify left bottom)
				(hide yes)
			)
		)
		(property "Color" "Green"
			(at 230.505 63.5 90)
			(effects
				(font
					(size 1.27 1.27)
				)
				(justify left)
			)
		)
		(pin "1"
		)
		(pin "2"
		)
		(instances
			(project "jetson-agx-thor-baseboard"
				(path ""
					(reference "D41")
					(unit 1)
				)
			)
		)
	)
	(symbol
		(lib_id "antmicropower:GND")
		(at 210.82 222.25 0)
		(unit 1)
		(exclude_from_sim no)
		(in_bom yes)
		(on_board yes)
		(dnp no)
		(fields_autoplaced yes)
		(property "Reference" "#PWR0407"
			(at 210.82 228.6 0)
			(effects
				(font
					(size 1.27 1.27)
				)
				(justify left bottom)
				(hide yes)
			)
		)
		(property "Value" "GND"
			(at 210.82 226.06 0)
			(effects
				(font
					(size 1.27 1.27)
					(thickness 0.15)
				)
			)
		)
		(property "Footprint" ""
			(at 219.71 229.87 0)
			(effects
				(font
					(size 1.27 1.27)
					(thickness 0.15)
				)
				(justify left bottom)
				(hide yes)
			)
		)
		(property "Datasheet" ""
			(at 219.71 234.95 0)
			(effects
				(font
					(size 1.27 1.27)
					(thickness 0.15)
				)
				(justify left bottom)
				(hide yes)
			)
		)
		(property "Description" ""
			(at 210.82 222.25 0)
			(effects
				(font
					(size 1.27 1.27)
				)
				(hide yes)
			)
		)
		(property "Author" "Antmicro"
			(at 219.71 229.87 0)
			(effects
				(font
					(size 1.27 1.27)
					(thickness 0.15)
				)
				(justify left bottom)
				(hide yes)
			)
		)
		(property "License" "Apache-2.0"
			(at 219.71 232.41 0)
			(effects
				(font
					(size 1.27 1.27)
					(thickness 0.15)
				)
				(justify left bottom)
				(hide yes)
			)
		)
		(pin "1"
		)
		(instances
			(project "jetson-agx-thor-baseboard"
				(path ""
					(reference "#PWR0407")
					(unit 1)
				)
			)
		)
	)
	(symbol
		(lib_id "antmicroResistors0402:R_100k_0402")
		(at 44.45 229.87 270)
		(mirror x)
		(unit 1)
		(exclude_from_sim no)
		(in_bom yes)
		(on_board yes)
		(dnp no)
		(property "Reference" "R229"
			(at 43.18 226.06 90)
			(effects
				(font
					(size 1.27 1.27)
				)
				(justify right)
			)
		)
		(property "Value" "R_100k_0402"
			(at 31.75 209.55 0)
			(effects
				(font
					(size 1.27 1.27)
					(thickness 0.15)
				)
				(justify left bottom)
				(hide yes)
			)
		)
		(property "Footprint" "antmicro-footprints:R_0402_1005Metric"
			(at 29.21 209.55 0)
			(effects
				(font
					(size 1.27 1.27)
					(thickness 0.15)
				)
				(justify left bottom)
				(hide yes)
			)
		)
		(property "Datasheet" "https://www.bourns.com/docs/product-datasheets/cr.pdf"
			(at 26.67 209.55 0)
			(effects
				(font
					(size 1.27 1.27)
					(thickness 0.15)
				)
				(justify left bottom)
				(hide yes)
			)
		)
		(property "Description" "SMD Chip Resistor, 100 kohm, ± 1%, 62.5 mW, 0402 [1005 Metric], Thick Film, General Purpose"
			(at 44.45 229.87 0)
			(effects
				(font
					(size 1.27 1.27)
				)
				(hide yes)
			)
		)
		(property "Manufacturer" "Bourns"
			(at 21.59 209.55 0)
			(effects
				(font
					(size 1.27 1.27)
					(thickness 0.15)
				)
				(justify left bottom)
				(hide yes)
			)
		)
		(property "MPN" "CR0402-FX-1003GLF"
			(at 24.13 209.55 0)
			(effects
				(font
					(size 1.27 1.27)
					(thickness 0.15)
				)
				(justify left bottom)
				(hide yes)
			)
		)
		(property "Val" "100k"
			(at 43.18 228.6 90)
			(effects
				(font
					(size 1.27 1.27)
					(thickness 0.15)
				)
				(justify right)
			)
		)
		(property "License" "Apache-2.0"
			(at 19.05 209.55 0)
			(effects
				(font
					(size 1.27 1.27)
					(thickness 0.15)
				)
				(justify left bottom)
				(hide yes)
			)
		)
		(property "Author" "Antmicro"
			(at 16.51 209.55 0)
			(effects
				(font
					(size 1.27 1.27)
					(thickness 0.15)
				)
				(justify left bottom)
				(hide yes)
			)
		)
		(property "Tolerance" "1%"
			(at 34.29 209.55 0)
			(effects
				(font
					(size 1.27 1.27)
				)
				(justify left bottom)
				(hide yes)
			)
		)
		(pin "1"
		)
		(pin "2"
		)
		(instances
			(project "jetson-agx-thor-baseboard"
				(path ""
					(reference "R229")
					(unit 1)
				)
			)
		)
	)
	(symbol
		(lib_id "antmicroWire2BoardConnectors:JST_SH_1x4_SM04B-SRSS-TB-LF-SN")
		(at 330.2 74.93 0)
		(unit 1)
		(exclude_from_sim no)
		(in_bom yes)
		(on_board yes)
		(dnp no)
		(property "Reference" "J17"
			(at 334.01 71.12 0)
			(effects
				(font
					(size 1.27 1.27)
					(thickness 0.15)
				)
			)
		)
		(property "Value" "JST_SH_1x4_SM04B-SRSS-TB-LF-SN"
			(at 356.87 82.55 0)
			(effects
				(font
					(size 1.27 1.27)
					(thickness 0.15)
				)
				(justify left bottom)
				(hide yes)
			)
		)
		(property "Footprint" "antmicro-footprints:Conn_JST_SH_1x4_SM04B-SRSS-TB-LF-SN"
			(at 356.87 85.09 0)
			(effects
				(font
					(size 1.27 1.27)
					(thickness 0.15)
				)
				(justify left bottom)
				(hide yes)
			)
		)
		(property "Datasheet" "https://www.jst-mfg.com/product/pdf/eng/eSH.pdf"
			(at 356.87 87.63 0)
			(effects
				(font
					(size 1.27 1.27)
					(thickness 0.15)
				)
				(justify left bottom)
				(hide yes)
			)
		)
		(property "Description" "Pin Header, Right Angle, Wire-to-Board, 1 mm, 1 Rows, 4 Contacts, Surface Mount Right Angle, SH"
			(at 330.2 74.93 0)
			(effects
				(font
					(size 1.27 1.27)
				)
				(hide yes)
			)
		)
		(property "MPN" "SM04B-SRSS-TB(LF)(SN)"
			(at 337.185 80.01 90)
			(effects
				(font
					(size 1.27 1.27)
					(thickness 0.15)
				)
			)
		)
		(property "Manufacturer" "JST Automotive Connectors"
			(at 356.87 90.17 0)
			(effects
				(font
					(size 1.27 1.27)
					(thickness 0.15)
				)
				(justify left bottom)
				(hide yes)
			)
		)
		(property "Author" "Antmicro"
			(at 356.87 92.71 0)
			(effects
				(font
					(size 1.27 1.27)
					(thickness 0.15)
				)
				(justify left bottom)
				(hide yes)
			)
		)
		(property "License" "Apache-2.0"
			(at 356.87 95.25 0)
			(effects
				(font
					(size 1.27 1.27)
					(thickness 0.15)
				)
				(justify left bottom)
				(hide yes)
			)
		)
		(pin "1"
		)
		(pin "2"
		)
		(pin "3"
		)
		(pin "4"
		)
		(pin "MP"
		)
		(instances
			(project "jetson-agx-thor-baseboard"
				(path ""
					(reference "J17")
					(unit 1)
				)
			)
		)
	)
	(symbol
		(lib_id "antmicropower:GND")
		(at 323.85 153.67 0)
		(unit 1)
		(exclude_from_sim no)
		(in_bom yes)
		(on_board yes)
		(dnp no)
		(fields_autoplaced yes)
		(property "Reference" "#PWR0647"
			(at 323.85 160.02 0)
			(effects
				(font
					(size 1.27 1.27)
				)
				(justify left bottom)
				(hide yes)
			)
		)
		(property "Value" "GND"
			(at 323.85 157.48 0)
			(effects
				(font
					(size 1.27 1.27)
					(thickness 0.15)
				)
			)
		)
		(property "Footprint" ""
			(at 332.74 161.29 0)
			(effects
				(font
					(size 1.27 1.27)
					(thickness 0.15)
				)
				(justify left bottom)
				(hide yes)
			)
		)
		(property "Datasheet" ""
			(at 332.74 166.37 0)
			(effects
				(font
					(size 1.27 1.27)
					(thickness 0.15)
				)
				(justify left bottom)
				(hide yes)
			)
		)
		(property "Description" ""
			(at 323.85 153.67 0)
			(effects
				(font
					(size 1.27 1.27)
				)
				(hide yes)
			)
		)
		(property "Author" "Antmicro"
			(at 332.74 161.29 0)
			(effects
				(font
					(size 1.27 1.27)
					(thickness 0.15)
				)
				(justify left bottom)
				(hide yes)
			)
		)
		(property "License" "Apache-2.0"
			(at 332.74 163.83 0)
			(effects
				(font
					(size 1.27 1.27)
					(thickness 0.15)
				)
				(justify left bottom)
				(hide yes)
			)
		)
		(pin "1"
		)
		(instances
			(project "jetson-agx-thor-baseboard"
				(path ""
					(reference "#PWR0647")
					(unit 1)
				)
			)
		)
	)
	(symbol
		(lib_id "antmicroMemory:AT24CS01_SOIC8")
		(at 198.12 142.24 0)
		(unit 1)
		(exclude_from_sim no)
		(in_bom yes)
		(on_board yes)
		(dnp no)
		(property "Reference" "U54"
			(at 205.994 135.128 0)
			(effects
				(font
					(size 1.27 1.27)
					(thickness 0.15)
				)
			)
		)
		(property "Value" "AT24CS01_SOIC8"
			(at 233.68 147.32 0)
			(effects
				(font
					(size 1.27 1.27)
					(thickness 0.15)
				)
				(justify left bottom)
				(hide yes)
			)
		)
		(property "Footprint" "antmicro-footprints:SOIC-8_3.9x4.9x1.75mm_P1.27mm"
			(at 233.68 149.86 0)
			(effects
				(font
					(size 1.27 1.27)
					(thickness 0.15)
				)
				(justify left bottom)
				(hide yes)
			)
		)
		(property "Datasheet" "https://ww1.microchip.com/downloads/aemDocuments/documents/MPD/ProductDocuments/DataSheets/20006330A.pdf"
			(at 233.68 152.4 0)
			(effects
				(font
					(size 1.27 1.27)
					(thickness 0.15)
				)
				(justify left bottom)
				(hide yes)
			)
		)
		(property "Description" "EEPROM, 1 Kbit, 128 x 8bit, Serial I2C (2-Wire), 1 MHz, SOIC-8"
			(at 233.68 165.1 0)
			(effects
				(font
					(size 1.27 1.27)
				)
				(justify left bottom)
				(hide yes)
			)
		)
		(property "Manufacturer" "Microchip Technology"
			(at 233.68 154.94 0)
			(effects
				(font
					(size 1.27 1.27)
					(thickness 0.15)
				)
				(justify left bottom)
				(hide yes)
			)
		)
		(property "MPN" "AT24CS01-SSHM-B"
			(at 205.994 137.668 0)
			(effects
				(font
					(size 1.27 1.27)
					(thickness 0.15)
				)
			)
		)
		(property "Author" "Antmicro"
			(at 233.68 160.02 0)
			(effects
				(font
					(size 1.27 1.27)
					(thickness 0.15)
				)
				(justify left bottom)
				(hide yes)
			)
		)
		(property "License" "Apache-2.0"
			(at 233.68 162.56 0)
			(effects
				(font
					(size 1.27 1.27)
					(thickness 0.15)
				)
				(justify left bottom)
				(hide yes)
			)
		)
		(pin "4"
		)
		(pin "5"
		)
		(pin "1"
		)
		(pin "3"
		)
		(pin "2"
		)
		(pin "7"
		)
		(pin "6"
		)
		(pin "8"
		)
		(instances
			(project ""
				(path ""
					(reference "U54")
					(unit 1)
				)
			)
		)
	)
	(symbol
		(lib_id "antmicroResistors0402:R_10k_0402")
		(at 278.13 129.54 90)
		(unit 1)
		(exclude_from_sim no)
		(in_bom yes)
		(on_board yes)
		(dnp no)
		(property "Reference" "R343"
			(at 279.4 125.73 90)
			(effects
				(font
					(size 1.27 1.27)
				)
				(justify right)
			)
		)
		(property "Value" "R_10k_0402"
			(at 290.83 109.22 0)
			(effects
				(font
					(size 1.27 1.27)
					(thickness 0.15)
				)
				(justify left bottom)
				(hide yes)
			)
		)
		(property "Footprint" "antmicro-footprints:R_0402_1005Metric"
			(at 293.37 109.22 0)
			(effects
				(font
					(size 1.27 1.27)
					(thickness 0.15)
				)
				(justify left bottom)
				(hide yes)
			)
		)
		(property "Datasheet" "https://www.bourns.com/docs/product-datasheets/cr.pdf"
			(at 295.91 109.22 0)
			(effects
				(font
					(size 1.27 1.27)
					(thickness 0.15)
				)
				(justify left bottom)
				(hide yes)
			)
		)
		(property "Description" "SMD Chip Resistor, 10 kohm, ± 1%, 62.5 mW, 0402 [1005 Metric], Thick Film, General Purpose"
			(at 278.13 129.54 0)
			(effects
				(font
					(size 1.27 1.27)
				)
				(hide yes)
			)
		)
		(property "Manufacturer" "Bourns"
			(at 300.99 109.22 0)
			(effects
				(font
					(size 1.27 1.27)
					(thickness 0.15)
				)
				(justify left bottom)
				(hide yes)
			)
		)
		(property "MPN" "CR0402-FX-1002GLF"
			(at 298.45 109.22 0)
			(effects
				(font
					(size 1.27 1.27)
					(thickness 0.15)
				)
				(justify left bottom)
				(hide yes)
			)
		)
		(property "Val" "10k"
			(at 279.4 128.27 90)
			(effects
				(font
					(size 1.27 1.27)
					(thickness 0.15)
				)
				(justify right)
			)
		)
		(property "License" "Apache-2.0"
			(at 303.53 109.22 0)
			(effects
				(font
					(size 1.27 1.27)
					(thickness 0.15)
				)
				(justify left bottom)
				(hide yes)
			)
		)
		(property "Author" "Antmicro"
			(at 306.07 109.22 0)
			(effects
				(font
					(size 1.27 1.27)
					(thickness 0.15)
				)
				(justify left bottom)
				(hide yes)
			)
		)
		(property "Tolerance" "1%"
			(at 288.29 109.22 0)
			(effects
				(font
					(size 1.27 1.27)
				)
				(justify left bottom)
				(hide yes)
			)
		)
		(pin "1"
		)
		(pin "2"
		)
		(instances
			(project "jetson-agx-thor-baseboard"
				(path ""
					(reference "R343")
					(unit 1)
				)
			)
		)
	)
	(symbol
		(lib_id "antmicroTVSDiodes:TPD4E05U06QDQARQ1")
		(at 110.49 149.86 270)
		(unit 1)
		(exclude_from_sim no)
		(in_bom yes)
		(on_board yes)
		(dnp no)
		(property "Reference" "U16"
			(at 98.552 160.02 90)
			(effects
				(font
					(size 1.27 1.27)
				)
				(justify left)
			)
		)
		(property "Value" "TPD4E05U06QDQARQ1"
			(at 100.33 173.99 0)
			(effects
				(font
					(size 1.27 1.27)
					(thickness 0.15)
				)
				(justify left bottom)
				(hide yes)
			)
		)
		(property "Footprint" "antmicro-footprints:USON-10_2.5x1mm_P0.5mm"
			(at 105.41 173.99 0)
			(effects
				(font
					(size 1.27 1.27)
					(thickness 0.15)
				)
				(justify left bottom)
				(hide yes)
			)
		)
		(property "Datasheet" "https://www.ti.com/lit/ds/symlink/tpd4e05u06-q1.pdf?HQS=dis-mous-null-mousermode-dsf-pf-null-wwe&ts=1663591265741&ref_url=https%253A%252F%252Fwww.mouser.com%252F"
			(at 102.87 173.99 0)
			(effects
				(font
					(size 1.27 1.27)
					(thickness 0.15)
				)
				(justify left bottom)
				(hide yes)
			)
		)
		(property "Description" "TVS diode array, 12 kV, USON-10, 5.5 V, 0.5 pF"
			(at 110.49 149.86 0)
			(effects
				(font
					(size 1.27 1.27)
				)
				(hide yes)
			)
		)
		(property "Manufacturer" "Texas Instruments"
			(at 97.79 173.99 0)
			(effects
				(font
					(size 1.27 1.27)
					(thickness 0.15)
				)
				(justify left bottom)
				(hide yes)
			)
		)
		(property "MPN" "TPD4E05U06QDQARQ1"
			(at 98.552 162.306 90)
			(effects
				(font
					(size 1.27 1.27)
					(thickness 0.15)
				)
				(justify left)
			)
		)
		(property "Author" "Antmicro"
			(at 95.25 173.99 0)
			(effects
				(font
					(size 1.27 1.27)
					(thickness 0.15)
				)
				(justify left bottom)
				(hide yes)
			)
		)
		(property "License" "Apache-2.0"
			(at 92.71 173.99 0)
			(effects
				(font
					(size 1.27 1.27)
					(thickness 0.15)
				)
				(justify left bottom)
				(hide yes)
			)
		)
		(pin "1"
		)
		(pin "10"
		)
		(pin "2"
		)
		(pin "3"
		)
		(pin "4"
		)
		(pin "5"
		)
		(pin "6"
		)
		(pin "7"
		)
		(pin "8"
		)
		(pin "9"
		)
		(instances
			(project "jetson-agx-thor-baseboard"
				(path ""
					(reference "U16")
					(unit 1)
				)
			)
		)
	)
	(symbol
		(lib_id "antmicropower:GND")
		(at 88.9 135.89 0)
		(unit 1)
		(exclude_from_sim no)
		(in_bom yes)
		(on_board yes)
		(dnp no)
		(fields_autoplaced yes)
		(property "Reference" "#PWR0572"
			(at 88.9 142.24 0)
			(effects
				(font
					(size 1.27 1.27)
				)
				(justify left bottom)
				(hide yes)
			)
		)
		(property "Value" "GND"
			(at 88.9 139.7 0)
			(effects
				(font
					(size 1.27 1.27)
					(thickness 0.15)
				)
			)
		)
		(property "Footprint" ""
			(at 97.79 143.51 0)
			(effects
				(font
					(size 1.27 1.27)
					(thickness 0.15)
				)
				(justify left bottom)
				(hide yes)
			)
		)
		(property "Datasheet" ""
			(at 97.79 148.59 0)
			(effects
				(font
					(size 1.27 1.27)
					(thickness 0.15)
				)
				(justify left bottom)
				(hide yes)
			)
		)
		(property "Description" ""
			(at 88.9 135.89 0)
			(effects
				(font
					(size 1.27 1.27)
				)
				(hide yes)
			)
		)
		(property "Author" "Antmicro"
			(at 97.79 143.51 0)
			(effects
				(font
					(size 1.27 1.27)
					(thickness 0.15)
				)
				(justify left bottom)
				(hide yes)
			)
		)
		(property "License" "Apache-2.0"
			(at 97.79 146.05 0)
			(effects
				(font
					(size 1.27 1.27)
					(thickness 0.15)
				)
				(justify left bottom)
				(hide yes)
			)
		)
		(pin "1"
		)
		(instances
			(project "jetson-agx-thor-baseboard"
				(path ""
					(reference "#PWR0572")
					(unit 1)
				)
			)
		)
	)
	(symbol
		(lib_id "antmicroLEDIndicationDiscrete:LED_G_0603_LTST-C190GKT")
		(at 316.23 64.77 270)
		(mirror x)
		(unit 1)
		(exclude_from_sim no)
		(in_bom yes)
		(on_board yes)
		(dnp no)
		(property "Reference" "D44"
			(at 319.405 60.96 90)
			(effects
				(font
					(size 1.27 1.27)
				)
				(justify left)
			)
		)
		(property "Value" "LED_G_0603_LTST-C190GKT"
			(at 308.61 41.91 0)
			(effects
				(font
					(size 1.27 1.27)
					(thickness 0.15)
				)
				(justify left bottom)
				(hide yes)
			)
		)
		(property "Footprint" "antmicro-footprints:LED_0603_1608Metric_G"
			(at 306.07 41.91 0)
			(effects
				(font
					(size 1.27 1.27)
					(thickness 0.15)
				)
				(justify left bottom)
				(hide yes)
			)
		)
		(property "Datasheet" "https://media.digikey.com/pdf/Data%20Sheets/Lite-On%20PDFs/LTST-C190GKT.pdf"
			(at 303.53 41.91 0)
			(effects
				(font
					(size 1.27 1.27)
					(thickness 0.15)
				)
				(justify left bottom)
				(hide yes)
			)
		)
		(property "Description" "LED, Green, SMD, 0603, 20 mA, 2.1 V, 569 nm"
			(at 316.23 64.77 0)
			(effects
				(font
					(size 1.27 1.27)
				)
				(hide yes)
			)
		)
		(property "MPN" "LTST-C190GKT"
			(at 300.99 41.91 0)
			(effects
				(font
					(size 1.27 1.27)
					(thickness 0.15)
				)
				(justify left bottom)
				(hide yes)
			)
		)
		(property "Manufacturer" "Lite-On"
			(at 298.45 41.91 0)
			(effects
				(font
					(size 1.27 1.27)
					(thickness 0.15)
				)
				(justify left bottom)
				(hide yes)
			)
		)
		(property "Author" "Antmicro"
			(at 295.91 41.91 0)
			(effects
				(font
					(size 1.27 1.27)
					(thickness 0.15)
				)
				(justify left bottom)
				(hide yes)
			)
		)
		(property "License" "Apache-2.0"
			(at 293.37 41.91 0)
			(effects
				(font
					(size 1.27 1.27)
					(thickness 0.15)
				)
				(justify left bottom)
				(hide yes)
			)
		)
		(property "Color" "Green"
			(at 319.405 63.5 90)
			(effects
				(font
					(size 1.27 1.27)
				)
				(justify left)
			)
		)
		(pin "1"
		)
		(pin "2"
		)
		(instances
			(project "jetson-agx-thor-baseboard"
				(path ""
					(reference "D44")
					(unit 1)
				)
			)
		)
	)
	(symbol
		(lib_id "antmicropower:+1V8")
		(at 40.64 124.46 0)
		(unit 1)
		(exclude_from_sim no)
		(in_bom yes)
		(on_board yes)
		(dnp no)
		(property "Reference" "#PWR0384"
			(at 40.64 128.27 0)
			(effects
				(font
					(size 1.27 1.27)
				)
				(justify left bottom)
				(hide yes)
			)
		)
		(property "Value" "+1V8"
			(at 37.465 121.285 0)
			(effects
				(font
					(size 1.27 1.27)
					(thickness 0.15)
				)
				(justify left bottom)
			)
		)
		(property "Footprint" ""
			(at 55.88 132.08 0)
			(effects
				(font
					(size 1.27 1.27)
					(thickness 0.15)
				)
				(justify left bottom)
				(hide yes)
			)
		)
		(property "Datasheet" ""
			(at 55.88 134.62 0)
			(effects
				(font
					(size 1.27 1.27)
					(thickness 0.15)
				)
				(justify left bottom)
				(hide yes)
			)
		)
		(property "Description" ""
			(at 40.64 124.46 0)
			(effects
				(font
					(size 1.27 1.27)
				)
				(hide yes)
			)
		)
		(property "Author" "Antmicro"
			(at 55.88 129.54 0)
			(effects
				(font
					(size 1.27 1.27)
					(thickness 0.15)
				)
				(justify left bottom)
				(hide yes)
			)
		)
		(property "License" "Apache-2.0"
			(at 55.88 132.08 0)
			(effects
				(font
					(size 1.27 1.27)
					(thickness 0.15)
				)
				(justify left bottom)
				(hide yes)
			)
		)
		(pin "1"
		)
		(instances
			(project "jetson-agx-thor-baseboard"
				(path ""
					(reference "#PWR0384")
					(unit 1)
				)
			)
		)
	)
	(symbol
		(lib_id "antmicropower:+3V3_AON")
		(at 232.41 139.7 0)
		(unit 1)
		(exclude_from_sim no)
		(in_bom yes)
		(on_board yes)
		(dnp no)
		(property "Reference" "#PWR0416"
			(at 232.41 143.51 0)
			(effects
				(font
					(size 1.27 1.27)
				)
				(hide yes)
			)
		)
		(property "Value" "+3V3_AON"
			(at 226.568 135.382 0)
			(effects
				(font
					(size 1.27 1.27)
				)
				(justify left)
			)
		)
		(property "Footprint" ""
			(at 232.41 139.7 0)
			(effects
				(font
					(size 1.27 1.27)
				)
				(hide yes)
			)
		)
		(property "Datasheet" ""
			(at 232.41 139.7 0)
			(effects
				(font
					(size 1.27 1.27)
				)
				(hide yes)
			)
		)
		(property "Description" ""
			(at 232.41 139.7 0)
			(effects
				(font
					(size 1.27 1.27)
				)
				(hide yes)
			)
		)
		(pin "1"
		)
		(instances
			(project "jetson-agx-thor-baseboard"
				(path ""
					(reference "#PWR0416")
					(unit 1)
				)
			)
		)
	)
	(symbol
		(lib_id "antmicropower:GND")
		(at 53.34 231.14 0)
		(unit 1)
		(exclude_from_sim no)
		(in_bom yes)
		(on_board yes)
		(dnp no)
		(fields_autoplaced yes)
		(property "Reference" "#PWR0392"
			(at 53.34 237.49 0)
			(effects
				(font
					(size 1.27 1.27)
				)
				(justify left bottom)
				(hide yes)
			)
		)
		(property "Value" "GND"
			(at 53.34 234.95 0)
			(effects
				(font
					(size 1.27 1.27)
					(thickness 0.15)
				)
			)
		)
		(property "Footprint" ""
			(at 62.23 238.76 0)
			(effects
				(font
					(size 1.27 1.27)
					(thickness 0.15)
				)
				(justify left bottom)
				(hide yes)
			)
		)
		(property "Datasheet" ""
			(at 62.23 243.84 0)
			(effects
				(font
					(size 1.27 1.27)
					(thickness 0.15)
				)
				(justify left bottom)
				(hide yes)
			)
		)
		(property "Description" ""
			(at 53.34 231.14 0)
			(effects
				(font
					(size 1.27 1.27)
				)
				(hide yes)
			)
		)
		(property "Author" "Antmicro"
			(at 62.23 238.76 0)
			(effects
				(font
					(size 1.27 1.27)
					(thickness 0.15)
				)
				(justify left bottom)
				(hide yes)
			)
		)
		(property "License" "Apache-2.0"
			(at 62.23 241.3 0)
			(effects
				(font
					(size 1.27 1.27)
					(thickness 0.15)
				)
				(justify left bottom)
				(hide yes)
			)
		)
		(pin "1"
		)
		(instances
			(project "jetson-agx-thor-baseboard"
				(path ""
					(reference "#PWR0392")
					(unit 1)
				)
			)
		)
	)
	(symbol
		(lib_id "antmicroLEDIndicationDiscrete:LED_G_0603_LTST-C190GKT")
		(at 102.87 214.63 90)
		(unit 1)
		(exclude_from_sim no)
		(in_bom yes)
		(on_board yes)
		(dnp no)
		(property "Reference" "D36"
			(at 104.14 210.82 90)
			(effects
				(font
					(size 1.27 1.27)
				)
				(justify right)
			)
		)
		(property "Value" "LED_G_0603_LTST-C190GKT"
			(at 110.49 191.77 0)
			(effects
				(font
					(size 1.27 1.27)
					(thickness 0.15)
				)
				(justify left bottom)
				(hide yes)
			)
		)
		(property "Footprint" "antmicro-footprints:LED_0603_1608Metric_G"
			(at 113.03 191.77 0)
			(effects
				(font
					(size 1.27 1.27)
					(thickness 0.15)
				)
				(justify left bottom)
				(hide yes)
			)
		)
		(property "Datasheet" "https://media.digikey.com/pdf/Data%20Sheets/Lite-On%20PDFs/LTST-C190GKT.pdf"
			(at 115.57 191.77 0)
			(effects
				(font
					(size 1.27 1.27)
					(thickness 0.15)
				)
				(justify left bottom)
				(hide yes)
			)
		)
		(property "Description" "LED, Green, SMD, 0603, 20 mA, 2.1 V, 569 nm"
			(at 102.87 214.63 0)
			(effects
				(font
					(size 1.27 1.27)
				)
				(hide yes)
			)
		)
		(property "MPN" "LTST-C190GKT"
			(at 118.11 191.77 0)
			(effects
				(font
					(size 1.27 1.27)
					(thickness 0.15)
				)
				(justify left bottom)
				(hide yes)
			)
		)
		(property "Manufacturer" "Lite-On"
			(at 120.65 191.77 0)
			(effects
				(font
					(size 1.27 1.27)
					(thickness 0.15)
				)
				(justify left bottom)
				(hide yes)
			)
		)
		(property "Author" "Antmicro"
			(at 123.19 191.77 0)
			(effects
				(font
					(size 1.27 1.27)
					(thickness 0.15)
				)
				(justify left bottom)
				(hide yes)
			)
		)
		(property "License" "Apache-2.0"
			(at 125.73 191.77 0)
			(effects
				(font
					(size 1.27 1.27)
					(thickness 0.15)
				)
				(justify left bottom)
				(hide yes)
			)
		)
		(property "Color" "Green"
			(at 104.14 213.36 90)
			(effects
				(font
					(size 1.27 1.27)
				)
				(justify right)
			)
		)
		(pin "1"
		)
		(pin "2"
		)
		(instances
			(project "jetson-agx-thor-baseboard"
				(path ""
					(reference "D36")
					(unit 1)
				)
			)
		)
	)
	(symbol
		(lib_id "antmicropower:GND")
		(at 76.2 38.1 0)
		(unit 1)
		(exclude_from_sim no)
		(in_bom yes)
		(on_board yes)
		(dnp no)
		(fields_autoplaced yes)
		(property "Reference" "#PWR0122"
			(at 76.2 44.45 0)
			(effects
				(font
					(size 1.27 1.27)
				)
				(justify left bottom)
				(hide yes)
			)
		)
		(property "Value" "GND"
			(at 76.2 41.91 0)
			(effects
				(font
					(size 1.27 1.27)
					(thickness 0.15)
				)
			)
		)
		(property "Footprint" ""
			(at 85.09 45.72 0)
			(effects
				(font
					(size 1.27 1.27)
					(thickness 0.15)
				)
				(justify left bottom)
				(hide yes)
			)
		)
		(property "Datasheet" ""
			(at 85.09 50.8 0)
			(effects
				(font
					(size 1.27 1.27)
					(thickness 0.15)
				)
				(justify left bottom)
				(hide yes)
			)
		)
		(property "Description" ""
			(at 76.2 38.1 0)
			(effects
				(font
					(size 1.27 1.27)
				)
				(hide yes)
			)
		)
		(property "Author" "Antmicro"
			(at 85.09 45.72 0)
			(effects
				(font
					(size 1.27 1.27)
					(thickness 0.15)
				)
				(justify left bottom)
				(hide yes)
			)
		)
		(property "License" "Apache-2.0"
			(at 85.09 48.26 0)
			(effects
				(font
					(size 1.27 1.27)
					(thickness 0.15)
				)
				(justify left bottom)
				(hide yes)
			)
		)
		(pin "1"
		)
		(instances
			(project "jetson-agx-thor-baseboard"
				(path ""
					(reference "#PWR0122")
					(unit 1)
				)
			)
		)
	)
	(symbol
		(lib_id "antmicroResistors0402:R_0R_0402")
		(at 342.9 129.54 0)
		(unit 1)
		(exclude_from_sim no)
		(in_bom yes)
		(on_board yes)
		(dnp no)
		(property "Reference" "R401"
			(at 340.868 128.524 0)
			(effects
				(font
					(size 1.27 1.27)
					(thickness 0.15)
				)
			)
		)
		(property "Value" "R_0R_0402"
			(at 363.22 142.24 0)
			(effects
				(font
					(size 1.27 1.27)
					(thickness 0.15)
				)
				(justify left bottom)
				(hide yes)
			)
		)
		(property "Footprint" "antmicro-footprints:R_0402_1005Metric"
			(at 363.22 144.78 0)
			(effects
				(font
					(size 1.27 1.27)
					(thickness 0.15)
				)
				(justify left bottom)
				(hide yes)
			)
		)
		(property "Datasheet" "https://industrial.panasonic.com/cdbs/www-data/pdf/RDA0000/AOA0000C301.pdf"
			(at 363.22 147.32 0)
			(effects
				(font
					(size 1.27 1.27)
					(thickness 0.15)
				)
				(justify left bottom)
				(hide yes)
			)
		)
		(property "Description" "SMD Chip Resistor, Jumper, 0 ohm, 100 mW, 0402 [1005 Metric], Thick Film, General Purpose"
			(at 363.22 162.56 0)
			(effects
				(font
					(size 1.27 1.27)
				)
				(justify left bottom)
				(hide yes)
			)
		)
		(property "MPN" "ERJ2GE0R00X"
			(at 363.22 149.86 0)
			(effects
				(font
					(size 1.27 1.27)
					(thickness 0.15)
				)
				(justify left bottom)
				(hide yes)
			)
		)
		(property "Manufacturer" "Panasonic"
			(at 363.22 152.4 0)
			(effects
				(font
					(size 1.27 1.27)
					(thickness 0.15)
				)
				(justify left bottom)
				(hide yes)
			)
		)
		(property "License" "Apache-2.0"
			(at 363.22 154.94 0)
			(effects
				(font
					(size 1.27 1.27)
					(thickness 0.15)
				)
				(justify left bottom)
				(hide yes)
			)
		)
		(property "Author" "Antmicro"
			(at 363.22 157.48 0)
			(effects
				(font
					(size 1.27 1.27)
					(thickness 0.15)
				)
				(justify left bottom)
				(hide yes)
			)
		)
		(property "Val" "0R"
			(at 348.742 128.524 0)
			(effects
				(font
					(size 1.27 1.27)
					(thickness 0.15)
				)
			)
		)
		(property "Tolerance" "~"
			(at 363.22 139.7 0)
			(effects
				(font
					(size 1.27 1.27)
				)
				(justify left bottom)
				(hide yes)
			)
		)
		(property "Current" "1A"
			(at 363.22 160.02 0)
			(effects
				(font
					(size 1.27 1.27)
					(thickness 0.15)
				)
				(justify left bottom)
				(hide yes)
			)
		)
		(pin "2"
		)
		(pin "1"
		)
		(instances
			(project ""
				(path ""
					(reference "R401")
					(unit 1)
				)
			)
		)
	)
	(symbol
		(lib_id "antmicroCapacitors0402:C_100n_0402")
		(at 58.42 36.83 90)
		(unit 1)
		(exclude_from_sim no)
		(in_bom yes)
		(on_board yes)
		(dnp no)
		(property "Reference" "C204"
			(at 59.944 33.02 90)
			(effects
				(font
					(size 1.27 1.27)
					(thickness 0.15)
				)
				(justify right)
			)
		)
		(property "Value" "C_100n_0402"
			(at 81.28 21.59 0)
			(effects
				(font
					(size 1.27 1.27)
					(thickness 0.15)
				)
				(justify left bottom)
				(hide yes)
			)
		)
		(property "Footprint" "antmicro-footprints:C_0402_1005Metric"
			(at 83.82 21.59 0)
			(effects
				(font
					(size 1.27 1.27)
					(thickness 0.15)
				)
				(justify left bottom)
				(hide yes)
			)
		)
		(property "Datasheet" "https://www.murata.com/products/productdetail?partno=GRM155R61H104KE14%23"
			(at 86.36 21.59 0)
			(effects
				(font
					(size 1.27 1.27)
					(thickness 0.15)
				)
				(justify left bottom)
				(hide yes)
			)
		)
		(property "Description" "SMD Multilayer Ceramic Capacitor, 0.1 µF, 50 V, 0402 [1005 Metric], ± 10%, X5R, GRM Series"
			(at 58.42 36.83 0)
			(effects
				(font
					(size 1.27 1.27)
				)
				(hide yes)
			)
		)
		(property "MPN" "GRM155R61H104KE14D"
			(at 88.9 21.59 0)
			(effects
				(font
					(size 1.27 1.27)
					(thickness 0.15)
				)
				(justify left bottom)
				(hide yes)
			)
		)
		(property "Val" "100n"
			(at 59.944 35.56 90)
			(effects
				(font
					(size 1.27 1.27)
					(thickness 0.15)
				)
				(justify right)
			)
		)
		(property "Voltage" "50V"
			(at 68.58 21.59 0)
			(effects
				(font
					(size 1.27 1.27)
					(thickness 0.15)
				)
				(justify left bottom)
				(hide yes)
			)
		)
		(property "Dielectric" "X5R"
			(at 71.12 21.59 0)
			(effects
				(font
					(size 1.27 1.27)
					(thickness 0.15)
				)
				(justify left bottom)
				(hide yes)
			)
		)
		(property "Manufacturer" "Murata"
			(at 73.66 21.59 0)
			(effects
				(font
					(size 1.27 1.27)
					(thickness 0.15)
				)
				(justify left bottom)
				(hide yes)
			)
		)
		(property "License" "Apache-2.0"
			(at 76.2 21.59 0)
			(effects
				(font
					(size 1.27 1.27)
					(thickness 0.15)
				)
				(justify left bottom)
				(hide yes)
			)
		)
		(property "Author" "Antmicro"
			(at 78.74 21.59 0)
			(effects
				(font
					(size 1.27 1.27)
					(thickness 0.15)
				)
				(justify left bottom)
				(hide yes)
			)
		)
		(pin "1"
		)
		(pin "2"
		)
		(instances
			(project "jetson-agx-thor-baseboard"
				(path ""
					(reference "C204")
					(unit 1)
				)
			)
		)
	)
	(symbol
		(lib_id "antmicropower:GND")
		(at 316.23 66.04 0)
		(unit 1)
		(exclude_from_sim no)
		(in_bom yes)
		(on_board yes)
		(dnp no)
		(fields_autoplaced yes)
		(property "Reference" "#PWR0425"
			(at 316.23 72.39 0)
			(effects
				(font
					(size 1.27 1.27)
				)
				(justify left bottom)
				(hide yes)
			)
		)
		(property "Value" "GND"
			(at 316.23 69.85 0)
			(effects
				(font
					(size 1.27 1.27)
					(thickness 0.15)
				)
			)
		)
		(property "Footprint" ""
			(at 325.12 73.66 0)
			(effects
				(font
					(size 1.27 1.27)
					(thickness 0.15)
				)
				(justify left bottom)
				(hide yes)
			)
		)
		(property "Datasheet" ""
			(at 325.12 78.74 0)
			(effects
				(font
					(size 1.27 1.27)
					(thickness 0.15)
				)
				(justify left bottom)
				(hide yes)
			)
		)
		(property "Description" ""
			(at 316.23 66.04 0)
			(effects
				(font
					(size 1.27 1.27)
				)
				(hide yes)
			)
		)
		(property "Author" "Antmicro"
			(at 325.12 73.66 0)
			(effects
				(font
					(size 1.27 1.27)
					(thickness 0.15)
				)
				(justify left bottom)
				(hide yes)
			)
		)
		(property "License" "Apache-2.0"
			(at 325.12 76.2 0)
			(effects
				(font
					(size 1.27 1.27)
					(thickness 0.15)
				)
				(justify left bottom)
				(hide yes)
			)
		)
		(pin "1"
		)
		(instances
			(project "jetson-agx-thor-baseboard"
				(path ""
					(reference "#PWR0425")
					(unit 1)
				)
			)
		)
	)
	(symbol
		(lib_id "antmicroResistors0402:R_0R_0402")
		(at 295.91 146.05 0)
		(unit 1)
		(exclude_from_sim no)
		(in_bom yes)
		(on_board yes)
		(dnp no)
		(property "Reference" "R344"
			(at 295.402 144.018 0)
			(effects
				(font
					(size 1.27 1.27)
				)
				(justify left)
			)
		)
		(property "Value" "R_0R_0402"
			(at 316.23 158.75 0)
			(effects
				(font
					(size 1.27 1.27)
					(thickness 0.15)
				)
				(justify left bottom)
				(hide yes)
			)
		)
		(property "Footprint" "antmicro-footprints:R_0402_1005Metric"
			(at 316.23 161.29 0)
			(effects
				(font
					(size 1.27 1.27)
					(thickness 0.15)
				)
				(justify left bottom)
				(hide yes)
			)
		)
		(property "Datasheet" "https://industrial.panasonic.com/cdbs/www-data/pdf/RDA0000/AOA0000C301.pdf"
			(at 316.23 163.83 0)
			(effects
				(font
					(size 1.27 1.27)
					(thickness 0.15)
				)
				(justify left bottom)
				(hide yes)
			)
		)
		(property "Description" "SMD Chip Resistor, Jumper, 0 ohm, 100 mW, 0402 [1005 Metric], Thick Film, General Purpose"
			(at 295.91 146.05 0)
			(effects
				(font
					(size 1.27 1.27)
				)
				(hide yes)
			)
		)
		(property "Manufacturer" "Panasonic"
			(at 316.23 168.91 0)
			(effects
				(font
					(size 1.27 1.27)
					(thickness 0.15)
				)
				(justify left bottom)
				(hide yes)
			)
		)
		(property "MPN" "ERJ2GE0R00X"
			(at 316.23 166.37 0)
			(effects
				(font
					(size 1.27 1.27)
					(thickness 0.15)
				)
				(justify left bottom)
				(hide yes)
			)
		)
		(property "Val" "0R"
			(at 297.18 148.336 0)
			(effects
				(font
					(size 1.27 1.27)
					(thickness 0.15)
				)
				(justify left)
			)
		)
		(property "License" "Apache-2.0"
			(at 316.23 171.45 0)
			(effects
				(font
					(size 1.27 1.27)
					(thickness 0.15)
				)
				(justify left bottom)
				(hide yes)
			)
		)
		(property "Author" "Antmicro"
			(at 316.23 173.99 0)
			(effects
				(font
					(size 1.27 1.27)
					(thickness 0.15)
				)
				(justify left bottom)
				(hide yes)
			)
		)
		(property "Tolerance" "~"
			(at 316.23 156.21 0)
			(effects
				(font
					(size 1.27 1.27)
				)
				(justify left bottom)
				(hide yes)
			)
		)
		(property "Current" "1A"
			(at 316.23 176.53 0)
			(effects
				(font
					(size 1.27 1.27)
					(thickness 0.15)
				)
				(justify left bottom)
				(hide yes)
			)
		)
		(pin "1"
		)
		(pin "2"
		)
		(instances
			(project "jetson-agx-thor-baseboard"
				(path ""
					(reference "R344")
					(unit 1)
				)
			)
		)
	)
	(symbol
		(lib_id "antmicroResistors0402:R_100k_0402")
		(at 190.5 60.96 90)
		(unit 1)
		(exclude_from_sim no)
		(in_bom no)
		(on_board yes)
		(dnp yes)
		(property "Reference" "R236"
			(at 191.77 57.15 90)
			(effects
				(font
					(size 1.27 1.27)
				)
				(justify right)
			)
		)
		(property "Value" "R_100k_0402"
			(at 203.2 40.64 0)
			(effects
				(font
					(size 1.27 1.27)
					(thickness 0.15)
				)
				(justify left bottom)
				(hide yes)
			)
		)
		(property "Footprint" "antmicro-footprints:R_0402_1005Metric"
			(at 205.74 40.64 0)
			(effects
				(font
					(size 1.27 1.27)
					(thickness 0.15)
				)
				(justify left bottom)
				(hide yes)
			)
		)
		(property "Datasheet" "https://www.bourns.com/docs/product-datasheets/cr.pdf"
			(at 208.28 40.64 0)
			(effects
				(font
					(size 1.27 1.27)
					(thickness 0.15)
				)
				(justify left bottom)
				(hide yes)
			)
		)
		(property "Description" "SMD Chip Resistor, 100 kohm, ± 1%, 62.5 mW, 0402 [1005 Metric], Thick Film, General Purpose"
			(at 190.5 60.96 0)
			(effects
				(font
					(size 1.27 1.27)
				)
				(hide yes)
			)
		)
		(property "Manufacturer" "Bourns"
			(at 213.36 40.64 0)
			(effects
				(font
					(size 1.27 1.27)
					(thickness 0.15)
				)
				(justify left bottom)
				(hide yes)
			)
		)
		(property "MPN" "CR0402-FX-1003GLF"
			(at 210.82 40.64 0)
			(effects
				(font
					(size 1.27 1.27)
					(thickness 0.15)
				)
				(justify left bottom)
				(hide yes)
			)
		)
		(property "Val" "100k"
			(at 191.77 59.69 90)
			(effects
				(font
					(size 1.27 1.27)
					(thickness 0.15)
				)
				(justify right)
			)
		)
		(property "License" "Apache-2.0"
			(at 215.9 40.64 0)
			(effects
				(font
					(size 1.27 1.27)
					(thickness 0.15)
				)
				(justify left bottom)
				(hide yes)
			)
		)
		(property "Author" "Antmicro"
			(at 218.44 40.64 0)
			(effects
				(font
					(size 1.27 1.27)
					(thickness 0.15)
				)
				(justify left bottom)
				(hide yes)
			)
		)
		(property "Tolerance" "1%"
			(at 200.66 40.64 0)
			(effects
				(font
					(size 1.27 1.27)
				)
				(justify left bottom)
				(hide yes)
			)
		)
		(pin "1"
		)
		(pin "2"
		)
		(instances
			(project "jetson-agx-thor-baseboard"
				(path ""
					(reference "R236")
					(unit 1)
				)
			)
		)
	)
	(symbol
		(lib_id "antmicroResistors0402:R_200R_0402")
		(at 102.87 208.28 90)
		(unit 1)
		(exclude_from_sim no)
		(in_bom yes)
		(on_board yes)
		(dnp no)
		(property "Reference" "R234"
			(at 104.14 204.47 90)
			(effects
				(font
					(size 1.27 1.27)
				)
				(justify right)
			)
		)
		(property "Value" "R_200R_0402"
			(at 115.57 187.96 0)
			(effects
				(font
					(size 1.27 1.27)
					(thickness 0.15)
				)
				(justify left bottom)
				(hide yes)
			)
		)
		(property "Footprint" "antmicro-footprints:R_0402_1005Metric"
			(at 118.11 187.96 0)
			(effects
				(font
					(size 1.27 1.27)
					(thickness 0.15)
				)
				(justify left bottom)
				(hide yes)
			)
		)
		(property "Datasheet" "https://www.bourns.com/docs/product-datasheets/cr.pdf"
			(at 120.65 187.96 0)
			(effects
				(font
					(size 1.27 1.27)
					(thickness 0.15)
				)
				(justify left bottom)
				(hide yes)
			)
		)
		(property "Description" "SMD Chip Resistor, 200 ohm, ± 1%, 62.5 mW, 0402 [1005 Metric], Thick Film, General Purpose"
			(at 102.87 208.28 0)
			(effects
				(font
					(size 1.27 1.27)
				)
				(hide yes)
			)
		)
		(property "Manufacturer" "Bourns"
			(at 125.73 187.96 0)
			(effects
				(font
					(size 1.27 1.27)
					(thickness 0.15)
				)
				(justify left bottom)
				(hide yes)
			)
		)
		(property "MPN" "CR0402-FX-2000GLF"
			(at 123.19 187.96 0)
			(effects
				(font
					(size 1.27 1.27)
					(thickness 0.15)
				)
				(justify left bottom)
				(hide yes)
			)
		)
		(property "Val" "200R"
			(at 104.14 207.01 90)
			(effects
				(font
					(size 1.27 1.27)
					(thickness 0.15)
				)
				(justify right)
			)
		)
		(property "License" "Apache-2.0"
			(at 128.27 187.96 0)
			(effects
				(font
					(size 1.27 1.27)
					(thickness 0.15)
				)
				(justify left bottom)
				(hide yes)
			)
		)
		(property "Author" "Antmicro"
			(at 130.81 187.96 0)
			(effects
				(font
					(size 1.27 1.27)
					(thickness 0.15)
				)
				(justify left bottom)
				(hide yes)
			)
		)
		(property "Tolerance" "1%"
			(at 113.03 187.96 0)
			(effects
				(font
					(size 1.27 1.27)
				)
				(justify left bottom)
				(hide yes)
			)
		)
		(pin "1"
		)
		(pin "2"
		)
		(instances
			(project "jetson-agx-thor-baseboard"
				(path ""
					(reference "R234")
					(unit 1)
				)
			)
		)
	)
	(symbol
		(lib_id "antmicroTransistorsFETsMOSFETsSingle:DMG1012T-7")
		(at 46.99 223.52 0)
		(unit 1)
		(exclude_from_sim no)
		(in_bom yes)
		(on_board yes)
		(dnp no)
		(fields_autoplaced yes)
		(property "Reference" "Q13"
			(at 57.15 219.71 0)
			(effects
				(font
					(size 1.27 1.27)
					(thickness 0.15)
				)
				(justify left)
			)
		)
		(property "Value" "DMG1012T-7"
			(at 69.85 232.41 0)
			(effects
				(font
					(size 1.27 1.27)
					(thickness 0.15)
				)
				(justify left bottom)
				(hide yes)
			)
		)
		(property "Footprint" "antmicro-footprints:SOT-523"
			(at 69.85 234.95 0)
			(effects
				(font
					(size 1.27 1.27)
					(thickness 0.15)
				)
				(justify left bottom)
				(hide yes)
			)
		)
		(property "Datasheet" "https://www.diodes.com/assets/Datasheets/ds31783.pdf"
			(at 69.85 237.49 0)
			(effects
				(font
					(size 1.27 1.27)
					(thickness 0.15)
				)
				(justify left bottom)
				(hide yes)
			)
		)
		(property "Description" "Power MOSFET, N Channel, 20 V, 630 mA, 0.3 ohm, SOT-523, Surface Mount"
			(at 69.85 250.19 0)
			(effects
				(font
					(size 1.27 1.27)
				)
				(justify left bottom)
				(hide yes)
			)
		)
		(property "MPN" "DMG1012T-7"
			(at 57.15 222.25 0)
			(effects
				(font
					(size 1.27 1.27)
					(thickness 0.15)
				)
				(justify left)
			)
		)
		(property "Manufacturer" "Diodes Incorporated"
			(at 69.85 242.57 0)
			(effects
				(font
					(size 1.27 1.27)
					(thickness 0.15)
				)
				(justify left bottom)
				(hide yes)
			)
		)
		(property "Author" "Antmicro"
			(at 69.85 245.11 0)
			(effects
				(font
					(size 1.27 1.27)
					(thickness 0.15)
				)
				(justify left bottom)
				(hide yes)
			)
		)
		(property "License" "Apache-2.0"
			(at 69.85 247.65 0)
			(effects
				(font
					(size 1.27 1.27)
					(thickness 0.15)
				)
				(justify left bottom)
				(hide yes)
			)
		)
		(pin "3"
		)
		(pin "1"
		)
		(pin "2"
		)
		(instances
			(project "jetson-agx-thor-baseboard"
				(path ""
					(reference "Q13")
					(unit 1)
				)
			)
		)
	)
	(symbol
		(lib_id "antmicropower:GND")
		(at 93.98 231.14 0)
		(unit 1)
		(exclude_from_sim no)
		(in_bom yes)
		(on_board yes)
		(dnp no)
		(fields_autoplaced yes)
		(property "Reference" "#PWR0398"
			(at 93.98 237.49 0)
			(effects
				(font
					(size 1.27 1.27)
				)
				(justify left bottom)
				(hide yes)
			)
		)
		(property "Value" "GND"
			(at 93.98 234.95 0)
			(effects
				(font
					(size 1.27 1.27)
					(thickness 0.15)
				)
			)
		)
		(property "Footprint" ""
			(at 102.87 238.76 0)
			(effects
				(font
					(size 1.27 1.27)
					(thickness 0.15)
				)
				(justify left bottom)
				(hide yes)
			)
		)
		(property "Datasheet" ""
			(at 102.87 243.84 0)
			(effects
				(font
					(size 1.27 1.27)
					(thickness 0.15)
				)
				(justify left bottom)
				(hide yes)
			)
		)
		(property "Description" ""
			(at 93.98 231.14 0)
			(effects
				(font
					(size 1.27 1.27)
				)
				(hide yes)
			)
		)
		(property "Author" "Antmicro"
			(at 102.87 238.76 0)
			(effects
				(font
					(size 1.27 1.27)
					(thickness 0.15)
				)
				(justify left bottom)
				(hide yes)
			)
		)
		(property "License" "Apache-2.0"
			(at 102.87 241.3 0)
			(effects
				(font
					(size 1.27 1.27)
					(thickness 0.15)
				)
				(justify left bottom)
				(hide yes)
			)
		)
		(pin "1"
		)
		(instances
			(project "jetson-agx-thor-baseboard"
				(path ""
					(reference "#PWR0398")
					(unit 1)
				)
			)
		)
	)
	(symbol
		(lib_id "antmicropower:GND")
		(at 264.16 45.72 0)
		(unit 1)
		(exclude_from_sim no)
		(in_bom yes)
		(on_board yes)
		(dnp no)
		(fields_autoplaced yes)
		(property "Reference" "#PWR0419"
			(at 264.16 52.07 0)
			(effects
				(font
					(size 1.27 1.27)
				)
				(justify left bottom)
				(hide yes)
			)
		)
		(property "Value" "GND"
			(at 264.16 49.53 0)
			(effects
				(font
					(size 1.27 1.27)
					(thickness 0.15)
				)
			)
		)
		(property "Footprint" ""
			(at 273.05 53.34 0)
			(effects
				(font
					(size 1.27 1.27)
					(thickness 0.15)
				)
				(justify left bottom)
				(hide yes)
			)
		)
		(property "Datasheet" ""
			(at 273.05 58.42 0)
			(effects
				(font
					(size 1.27 1.27)
					(thickness 0.15)
				)
				(justify left bottom)
				(hide yes)
			)
		)
		(property "Description" ""
			(at 264.16 45.72 0)
			(effects
				(font
					(size 1.27 1.27)
				)
				(hide yes)
			)
		)
		(property "Author" "Antmicro"
			(at 273.05 53.34 0)
			(effects
				(font
					(size 1.27 1.27)
					(thickness 0.15)
				)
				(justify left bottom)
				(hide yes)
			)
		)
		(property "License" "Apache-2.0"
			(at 273.05 55.88 0)
			(effects
				(font
					(size 1.27 1.27)
					(thickness 0.15)
				)
				(justify left bottom)
				(hide yes)
			)
		)
		(pin "1"
		)
		(instances
			(project "jetson-agx-thor-baseboard"
				(path ""
					(reference "#PWR0419")
					(unit 1)
				)
			)
		)
	)
	(symbol
		(lib_id "antmicropower:+3V3")
		(at 53.34 201.93 0)
		(unit 1)
		(exclude_from_sim no)
		(in_bom yes)
		(on_board yes)
		(dnp no)
		(property "Reference" "#PWR0391"
			(at 53.34 205.74 0)
			(effects
				(font
					(size 1.27 1.27)
				)
				(justify left bottom)
				(hide yes)
			)
		)
		(property "Value" "+3V3"
			(at 50.165 198.12 0)
			(effects
				(font
					(size 1.27 1.27)
					(thickness 0.15)
				)
				(justify left)
			)
		)
		(property "Footprint" ""
			(at 68.58 209.55 0)
			(effects
				(font
					(size 1.27 1.27)
					(thickness 0.15)
				)
				(justify left bottom)
				(hide yes)
			)
		)
		(property "Datasheet" ""
			(at 68.58 212.09 0)
			(effects
				(font
					(size 1.27 1.27)
					(thickness 0.15)
				)
				(justify left bottom)
				(hide yes)
			)
		)
		(property "Description" ""
			(at 53.34 201.93 0)
			(effects
				(font
					(size 1.27 1.27)
				)
				(hide yes)
			)
		)
		(property "Author" "Antmicro"
			(at 68.58 204.47 0)
			(effects
				(font
					(size 1.27 1.27)
					(thickness 0.15)
				)
				(justify left bottom)
				(hide yes)
			)
		)
		(property "License" "Apache-2.0"
			(at 68.58 207.01 0)
			(effects
				(font
					(size 1.27 1.27)
					(thickness 0.15)
				)
				(justify left bottom)
				(hide yes)
			)
		)
		(pin "1"
		)
		(instances
			(project "jetson-agx-thor-baseboard"
				(path ""
					(reference "#PWR0391")
					(unit 1)
				)
			)
		)
	)
	(symbol
		(lib_id "antmicroInterfaceControllers:SLB9673AU20FW2610XTMA1")
		(at 87.63 50.8 0)
		(unit 1)
		(exclude_from_sim no)
		(in_bom yes)
		(on_board yes)
		(dnp no)
		(fields_autoplaced yes)
		(property "Reference" "U14"
			(at 121.92 69.85 0)
			(effects
				(font
					(size 1.27 1.27)
					(thickness 0.15)
				)
				(justify left)
			)
		)
		(property "Value" "SLB9673AU20FW2610XTMA1"
			(at 138.43 68.58 0)
			(effects
				(font
					(size 1.27 1.27)
					(thickness 0.15)
				)
				(justify left bottom)
				(hide yes)
			)
		)
		(property "Footprint" "antmicro-footprints:QFN-32-1EP_5x5mm"
			(at 138.43 71.12 0)
			(effects
				(font
					(size 1.27 1.27)
					(thickness 0.15)
				)
				(justify left bottom)
				(hide yes)
			)
		)
		(property "Datasheet" "https://eu.mouser.com/datasheet/2/196/Infineon_OPTIGA_TPM_SLB_9673_FW26_DataSheet_v01_30-3363760.pdf"
			(at 138.43 73.66 0)
			(effects
				(font
					(size 1.27 1.27)
					(thickness 0.15)
				)
				(justify left bottom)
				(hide yes)
			)
		)
		(property "Description" "Security ICs / Authentication ICs"
			(at 87.63 50.8 0)
			(effects
				(font
					(size 1.27 1.27)
				)
				(hide yes)
			)
		)
		(property "MPN" "SLB9673AU20FW2610XTMA1"
			(at 121.92 72.39 0)
			(effects
				(font
					(size 1.27 1.27)
					(thickness 0.15)
				)
				(justify left)
			)
		)
		(property "Manufacturer" "Infineon"
			(at 138.43 60.96 0)
			(effects
				(font
					(size 1.27 1.27)
					(thickness 0.15)
				)
				(justify left bottom)
				(hide yes)
			)
		)
		(property "Author" "Antmicro"
			(at 138.43 63.5 0)
			(effects
				(font
					(size 1.27 1.27)
					(thickness 0.15)
				)
				(justify left bottom)
				(hide yes)
			)
		)
		(property "License" "Apache-2.0"
			(at 138.43 66.04 0)
			(effects
				(font
					(size 1.27 1.27)
					(thickness 0.15)
				)
				(justify left bottom)
				(hide yes)
			)
		)
		(pin "23"
		)
		(pin "7"
		)
		(pin "10"
		)
		(pin "16"
		)
		(pin "6"
		)
		(pin "14"
		)
		(pin "31"
		)
		(pin "19"
		)
		(pin "11"
		)
		(pin "33"
		)
		(pin "2"
		)
		(pin "32"
		)
		(pin "24"
		)
		(pin "17"
		)
		(pin "26"
		)
		(pin "5"
		)
		(pin "29"
		)
		(pin "4"
		)
		(pin "20"
		)
		(pin "8"
		)
		(pin "22"
		)
		(pin "12"
		)
		(pin "21"
		)
		(pin "27"
		)
		(pin "30"
		)
		(pin "28"
		)
		(pin "25"
		)
		(pin "1"
		)
		(pin "9"
		)
		(pin "13"
		)
		(pin "18"
		)
		(pin "3"
		)
		(pin "15"
		)
		(instances
			(project ""
				(path ""
					(reference "U14")
					(unit 1)
				)
			)
		)
	)
	(symbol
		(lib_id "antmicropower:+1V8")
		(at 278.13 121.92 0)
		(unit 1)
		(exclude_from_sim no)
		(in_bom yes)
		(on_board yes)
		(dnp no)
		(property "Reference" "#PWR0642"
			(at 278.13 125.73 0)
			(effects
				(font
					(size 1.27 1.27)
				)
				(justify left bottom)
				(hide yes)
			)
		)
		(property "Value" "+1V8"
			(at 274.955 118.11 0)
			(effects
				(font
					(size 1.27 1.27)
					(thickness 0.15)
				)
				(justify left)
			)
		)
		(property "Footprint" ""
			(at 293.37 129.54 0)
			(effects
				(font
					(size 1.27 1.27)
					(thickness 0.15)
				)
				(justify left bottom)
				(hide yes)
			)
		)
		(property "Datasheet" ""
			(at 293.37 132.08 0)
			(effects
				(font
					(size 1.27 1.27)
					(thickness 0.15)
				)
				(justify left bottom)
				(hide yes)
			)
		)
		(property "Description" ""
			(at 278.13 121.92 0)
			(effects
				(font
					(size 1.27 1.27)
				)
				(hide yes)
			)
		)
		(property "Author" "Antmicro"
			(at 293.37 127 0)
			(effects
				(font
					(size 1.27 1.27)
					(thickness 0.15)
				)
				(justify left bottom)
				(hide yes)
			)
		)
		(property "License" "Apache-2.0"
			(at 293.37 129.54 0)
			(effects
				(font
					(size 1.27 1.27)
					(thickness 0.15)
				)
				(justify left bottom)
				(hide yes)
			)
		)
		(pin "1"
		)
		(instances
			(project "jetson-agx-thor-baseboard"
				(path ""
					(reference "#PWR0642")
					(unit 1)
				)
			)
		)
	)
	(symbol
		(lib_id "antmicropower:GND")
		(at 95.25 151.13 0)
		(unit 1)
		(exclude_from_sim no)
		(in_bom yes)
		(on_board yes)
		(dnp no)
		(property "Reference" "#PWR0571"
			(at 95.25 157.48 0)
			(effects
				(font
					(size 1.27 1.27)
				)
				(justify left bottom)
				(hide yes)
			)
		)
		(property "Value" "GND"
			(at 95.25 154.94 0)
			(effects
				(font
					(size 1.27 1.27)
					(thickness 0.15)
				)
			)
		)
		(property "Footprint" ""
			(at 104.14 158.75 0)
			(effects
				(font
					(size 1.27 1.27)
					(thickness 0.15)
				)
				(justify left bottom)
				(hide yes)
			)
		)
		(property "Datasheet" ""
			(at 104.14 163.83 0)
			(effects
				(font
					(size 1.27 1.27)
					(thickness 0.15)
				)
				(justify left bottom)
				(hide yes)
			)
		)
		(property "Description" ""
			(at 95.25 151.13 0)
			(effects
				(font
					(size 1.27 1.27)
				)
				(hide yes)
			)
		)
		(property "Author" "Antmicro"
			(at 104.14 158.75 0)
			(effects
				(font
					(size 1.27 1.27)
					(thickness 0.15)
				)
				(justify left bottom)
				(hide yes)
			)
		)
		(property "License" "Apache-2.0"
			(at 104.14 161.29 0)
			(effects
				(font
					(size 1.27 1.27)
					(thickness 0.15)
				)
				(justify left bottom)
				(hide yes)
			)
		)
		(pin "1"
		)
		(instances
			(project "jetson-agx-thor-baseboard"
				(path ""
					(reference "#PWR0571")
					(unit 1)
				)
			)
		)
	)
	(symbol
		(lib_id "antmicroTransistorsFETsMOSFETsSingle:DMG1012T-7")
		(at 96.52 223.52 0)
		(unit 1)
		(exclude_from_sim no)
		(in_bom yes)
		(on_board yes)
		(dnp no)
		(fields_autoplaced yes)
		(property "Reference" "Q14"
			(at 106.68 219.71 0)
			(effects
				(font
					(size 1.27 1.27)
					(thickness 0.15)
				)
				(justify left)
			)
		)
		(property "Value" "DMG1012T-7"
			(at 119.38 232.41 0)
			(effects
				(font
					(size 1.27 1.27)
					(thickness 0.15)
				)
				(justify left bottom)
				(hide yes)
			)
		)
		(property "Footprint" "antmicro-footprints:SOT-523"
			(at 119.38 234.95 0)
			(effects
				(font
					(size 1.27 1.27)
					(thickness 0.15)
				)
				(justify left bottom)
				(hide yes)
			)
		)
		(property "Datasheet" "https://www.diodes.com/assets/Datasheets/ds31783.pdf"
			(at 119.38 237.49 0)
			(effects
				(font
					(size 1.27 1.27)
					(thickness 0.15)
				)
				(justify left bottom)
				(hide yes)
			)
		)
		(property "Description" "Power MOSFET, N Channel, 20 V, 630 mA, 0.3 ohm, SOT-523, Surface Mount"
			(at 119.38 250.19 0)
			(effects
				(font
					(size 1.27 1.27)
				)
				(justify left bottom)
				(hide yes)
			)
		)
		(property "MPN" "DMG1012T-7"
			(at 106.68 222.25 0)
			(effects
				(font
					(size 1.27 1.27)
					(thickness 0.15)
				)
				(justify left)
			)
		)
		(property "Manufacturer" "Diodes Incorporated"
			(at 119.38 242.57 0)
			(effects
				(font
					(size 1.27 1.27)
					(thickness 0.15)
				)
				(justify left bottom)
				(hide yes)
			)
		)
		(property "Author" "Antmicro"
			(at 119.38 245.11 0)
			(effects
				(font
					(size 1.27 1.27)
					(thickness 0.15)
				)
				(justify left bottom)
				(hide yes)
			)
		)
		(property "License" "Apache-2.0"
			(at 119.38 247.65 0)
			(effects
				(font
					(size 1.27 1.27)
					(thickness 0.15)
				)
				(justify left bottom)
				(hide yes)
			)
		)
		(pin "3"
		)
		(pin "1"
		)
		(pin "2"
		)
		(instances
			(project "jetson-agx-thor-baseboard"
				(path ""
					(reference "Q14")
					(unit 1)
				)
			)
		)
	)
	(symbol
		(lib_id "antmicroPMICPowerDistributionSwitchesLoadDrivers:AP22615A_TSOT26")
		(at 195.58 49.53 0)
		(unit 1)
		(exclude_from_sim no)
		(in_bom yes)
		(on_board yes)
		(dnp no)
		(property "Reference" "U53"
			(at 203.2 43.18 0)
			(effects
				(font
					(size 1.27 1.27)
				)
			)
		)
		(property "Value" "AP22615A_TSOT26"
			(at 226.06 54.61 0)
			(effects
				(font
					(size 1.27 1.27)
					(thickness 0.15)
				)
				(justify left bottom)
				(hide yes)
			)
		)
		(property "Footprint" "antmicro-footprints:TSOT23-6"
			(at 226.06 57.15 0)
			(effects
				(font
					(size 1.27 1.27)
					(thickness 0.15)
				)
				(justify left bottom)
				(hide yes)
			)
		)
		(property "Datasheet" "https://www.mouser.com/datasheet/2/115/DIOD_S_A0008958405_1-2543193.pdf"
			(at 226.06 59.69 0)
			(effects
				(font
					(size 1.27 1.27)
					(thickness 0.15)
				)
				(justify left bottom)
				(hide yes)
			)
		)
		(property "Description" "Power Load Distribution Switch, High Side, Active High, 1 Output, 5.5 V, 3.6 A, 0.04 ohm, TSOT-26-6"
			(at 195.58 49.53 0)
			(effects
				(font
					(size 1.27 1.27)
				)
				(hide yes)
			)
		)
		(property "MPN" "AP22615AWU-7"
			(at 203.2 45.72 0)
			(effects
				(font
					(size 1.27 1.27)
					(thickness 0.15)
				)
			)
		)
		(property "Manufacturer" "Diodes Incorporated"
			(at 226.06 64.77 0)
			(effects
				(font
					(size 1.27 1.27)
					(thickness 0.15)
				)
				(justify left bottom)
				(hide yes)
			)
		)
		(property "Author" "Antmicro"
			(at 226.06 67.31 0)
			(effects
				(font
					(size 1.27 1.27)
					(thickness 0.15)
				)
				(justify left bottom)
				(hide yes)
			)
		)
		(property "License" "Apache-2.0"
			(at 226.06 69.85 0)
			(effects
				(font
					(size 1.27 1.27)
					(thickness 0.15)
				)
				(justify left bottom)
				(hide yes)
			)
		)
		(pin "1"
		)
		(pin "2"
		)
		(pin "3"
		)
		(pin "4"
		)
		(pin "5"
		)
		(pin "6"
		)
		(instances
			(project "jetson-agx-thor-baseboard"
				(path ""
					(reference "U53")
					(unit 1)
				)
			)
		)
	)
	(symbol
		(lib_id "antmicroResistors0402:R_10k_0402")
		(at 217.17 58.42 90)
		(unit 1)
		(exclude_from_sim no)
		(in_bom yes)
		(on_board yes)
		(dnp no)
		(property "Reference" "R241"
			(at 218.44 54.61 90)
			(effects
				(font
					(size 1.27 1.27)
				)
				(justify right)
			)
		)
		(property "Value" "R_10k_0402"
			(at 229.87 38.1 0)
			(effects
				(font
					(size 1.27 1.27)
					(thickness 0.15)
				)
				(justify left bottom)
				(hide yes)
			)
		)
		(property "Footprint" "antmicro-footprints:R_0402_1005Metric"
			(at 232.41 38.1 0)
			(effects
				(font
					(size 1.27 1.27)
					(thickness 0.15)
				)
				(justify left bottom)
				(hide yes)
			)
		)
		(property "Datasheet" "https://www.bourns.com/docs/product-datasheets/cr.pdf"
			(at 234.95 38.1 0)
			(effects
				(font
					(size 1.27 1.27)
					(thickness 0.15)
				)
				(justify left bottom)
				(hide yes)
			)
		)
		(property "Description" "SMD Chip Resistor, 10 kohm, ± 1%, 62.5 mW, 0402 [1005 Metric], Thick Film, General Purpose"
			(at 217.17 58.42 0)
			(effects
				(font
					(size 1.27 1.27)
				)
				(hide yes)
			)
		)
		(property "Manufacturer" "Bourns"
			(at 240.03 38.1 0)
			(effects
				(font
					(size 1.27 1.27)
					(thickness 0.15)
				)
				(justify left bottom)
				(hide yes)
			)
		)
		(property "MPN" "CR0402-FX-1002GLF"
			(at 237.49 38.1 0)
			(effects
				(font
					(size 1.27 1.27)
					(thickness 0.15)
				)
				(justify left bottom)
				(hide yes)
			)
		)
		(property "Val" "10k"
			(at 218.44 57.15 90)
			(effects
				(font
					(size 1.27 1.27)
					(thickness 0.15)
				)
				(justify right)
			)
		)
		(property "License" "Apache-2.0"
			(at 242.57 38.1 0)
			(effects
				(font
					(size 1.27 1.27)
					(thickness 0.15)
				)
				(justify left bottom)
				(hide yes)
			)
		)
		(property "Author" "Antmicro"
			(at 245.11 38.1 0)
			(effects
				(font
					(size 1.27 1.27)
					(thickness 0.15)
				)
				(justify left bottom)
				(hide yes)
			)
		)
		(property "Tolerance" "1%"
			(at 227.33 38.1 0)
			(effects
				(font
					(size 1.27 1.27)
				)
				(justify left bottom)
				(hide yes)
			)
		)
		(pin "1"
		)
		(pin "2"
		)
		(instances
			(project "jetson-agx-thor-baseboard"
				(path ""
					(reference "R241")
					(unit 1)
				)
			)
		)
	)
	(symbol
		(lib_id "antmicroTestPoints:TP_0.75mm_SMD")
		(at 326.39 49.53 90)
		(unit 1)
		(exclude_from_sim no)
		(in_bom no)
		(on_board yes)
		(dnp no)
		(property "Reference" "TP94"
			(at 328.422 43.942 90)
			(effects
				(font
					(size 1.27 1.27)
					(thickness 0.15)
				)
				(justify left)
			)
		)
		(property "Value" "TP_0.75mm_SMD"
			(at 330.2 39.37 0)
			(effects
				(font
					(size 1.27 1.27)
					(thickness 0.15)
				)
				(justify left bottom)
				(hide yes)
			)
		)
		(property "Footprint" "antmicro-footprints:TP_SMD_0.75mm"
			(at 332.74 39.37 0)
			(effects
				(font
					(size 1.27 1.27)
					(thickness 0.15)
				)
				(justify left bottom)
				(hide yes)
			)
		)
		(property "Datasheet" ""
			(at 339.09 31.75 0)
			(effects
				(font
					(size 1.27 1.27)
					(thickness 0.15)
				)
				(justify left bottom)
				(hide yes)
			)
		)
		(property "Description" "SMT test point"
			(at 326.39 49.53 0)
			(effects
				(font
					(size 1.27 1.27)
				)
				(hide yes)
			)
		)
		(property "MPN" ""
			(at 337.82 38.735 0)
			(effects
				(font
					(size 1.27 1.27)
					(thickness 0.15)
				)
				(justify left bottom)
				(hide yes)
			)
		)
		(property "Manufacturer" ""
			(at 332.74 38.735 0)
			(effects
				(font
					(size 1.27 1.27)
					(thickness 0.15)
				)
				(justify left bottom)
				(hide yes)
			)
		)
		(property "Author" "Antmicro"
			(at 335.28 39.37 0)
			(effects
				(font
					(size 1.27 1.27)
					(thickness 0.15)
				)
				(justify left bottom)
				(hide yes)
			)
		)
		(property "License" "Apache-2.0"
			(at 337.82 39.37 0)
			(effects
				(font
					(size 1.27 1.27)
					(thickness 0.15)
				)
				(justify left bottom)
				(hide yes)
			)
		)
		(pin "1"
		)
		(instances
			(project "jetson-agx-thor-baseboard"
				(path ""
					(reference "TP94")
					(unit 1)
				)
			)
		)
	)
	(symbol
		(lib_id "antmicroResistors0402:R_0R_0402")
		(at 342.9 134.62 0)
		(unit 1)
		(exclude_from_sim no)
		(in_bom yes)
		(on_board yes)
		(dnp no)
		(property "Reference" "R347"
			(at 340.868 133.604 0)
			(effects
				(font
					(size 1.27 1.27)
					(thickness 0.15)
				)
			)
		)
		(property "Value" "R_0R_0402"
			(at 363.22 147.32 0)
			(effects
				(font
					(size 1.27 1.27)
					(thickness 0.15)
				)
				(justify left bottom)
				(hide yes)
			)
		)
		(property "Footprint" "antmicro-footprints:R_0402_1005Metric"
			(at 363.22 149.86 0)
			(effects
				(font
					(size 1.27 1.27)
					(thickness 0.15)
				)
				(justify left bottom)
				(hide yes)
			)
		)
		(property "Datasheet" "https://industrial.panasonic.com/cdbs/www-data/pdf/RDA0000/AOA0000C301.pdf"
			(at 363.22 152.4 0)
			(effects
				(font
					(size 1.27 1.27)
					(thickness 0.15)
				)
				(justify left bottom)
				(hide yes)
			)
		)
		(property "Description" "SMD Chip Resistor, Jumper, 0 ohm, 100 mW, 0402 [1005 Metric], Thick Film, General Purpose"
			(at 363.22 167.64 0)
			(effects
				(font
					(size 1.27 1.27)
				)
				(justify left bottom)
				(hide yes)
			)
		)
		(property "MPN" "ERJ2GE0R00X"
			(at 363.22 154.94 0)
			(effects
				(font
					(size 1.27 1.27)
					(thickness 0.15)
				)
				(justify left bottom)
				(hide yes)
			)
		)
		(property "Manufacturer" "Panasonic"
			(at 363.22 157.48 0)
			(effects
				(font
					(size 1.27 1.27)
					(thickness 0.15)
				)
				(justify left bottom)
				(hide yes)
			)
		)
		(property "License" "Apache-2.0"
			(at 363.22 160.02 0)
			(effects
				(font
					(size 1.27 1.27)
					(thickness 0.15)
				)
				(justify left bottom)
				(hide yes)
			)
		)
		(property "Author" "Antmicro"
			(at 363.22 162.56 0)
			(effects
				(font
					(size 1.27 1.27)
					(thickness 0.15)
				)
				(justify left bottom)
				(hide yes)
			)
		)
		(property "Val" "0R"
			(at 348.742 133.604 0)
			(effects
				(font
					(size 1.27 1.27)
					(thickness 0.15)
				)
			)
		)
		(property "Tolerance" "~"
			(at 363.22 144.78 0)
			(effects
				(font
					(size 1.27 1.27)
				)
				(justify left bottom)
				(hide yes)
			)
		)
		(property "Current" "1A"
			(at 363.22 165.1 0)
			(effects
				(font
					(size 1.27 1.27)
					(thickness 0.15)
				)
				(justify left bottom)
				(hide yes)
			)
		)
		(pin "2"
		)
		(pin "1"
		)
		(instances
			(project "jetson-agx-thor-baseboard"
				(path ""
					(reference "R347")
					(unit 1)
				)
			)
		)
	)
	(symbol
		(lib_id "antmicroResistors0402:R_100k_0402")
		(at 93.98 229.87 90)
		(unit 1)
		(exclude_from_sim no)
		(in_bom yes)
		(on_board yes)
		(dnp no)
		(property "Reference" "R233"
			(at 92.71 226.06 90)
			(effects
				(font
					(size 1.27 1.27)
				)
				(justify left)
			)
		)
		(property "Value" "R_100k_0402"
			(at 106.68 209.55 0)
			(effects
				(font
					(size 1.27 1.27)
					(thickness 0.15)
				)
				(justify left bottom)
				(hide yes)
			)
		)
		(property "Footprint" "antmicro-footprints:R_0402_1005Metric"
			(at 109.22 209.55 0)
			(effects
				(font
					(size 1.27 1.27)
					(thickness 0.15)
				)
				(justify left bottom)
				(hide yes)
			)
		)
		(property "Datasheet" "https://www.bourns.com/docs/product-datasheets/cr.pdf"
			(at 111.76 209.55 0)
			(effects
				(font
					(size 1.27 1.27)
					(thickness 0.15)
				)
				(justify left bottom)
				(hide yes)
			)
		)
		(property "Description" "SMD Chip Resistor, 100 kohm, ± 1%, 62.5 mW, 0402 [1005 Metric], Thick Film, General Purpose"
			(at 93.98 229.87 0)
			(effects
				(font
					(size 1.27 1.27)
				)
				(hide yes)
			)
		)
		(property "Manufacturer" "Bourns"
			(at 116.84 209.55 0)
			(effects
				(font
					(size 1.27 1.27)
					(thickness 0.15)
				)
				(justify left bottom)
				(hide yes)
			)
		)
		(property "MPN" "CR0402-FX-1003GLF"
			(at 114.3 209.55 0)
			(effects
				(font
					(size 1.27 1.27)
					(thickness 0.15)
				)
				(justify left bottom)
				(hide yes)
			)
		)
		(property "Val" "100k"
			(at 92.71 228.6 90)
			(effects
				(font
					(size 1.27 1.27)
					(thickness 0.15)
				)
				(justify left)
			)
		)
		(property "License" "Apache-2.0"
			(at 119.38 209.55 0)
			(effects
				(font
					(size 1.27 1.27)
					(thickness 0.15)
				)
				(justify left bottom)
				(hide yes)
			)
		)
		(property "Author" "Antmicro"
			(at 121.92 209.55 0)
			(effects
				(font
					(size 1.27 1.27)
					(thickness 0.15)
				)
				(justify left bottom)
				(hide yes)
			)
		)
		(property "Tolerance" "1%"
			(at 104.14 209.55 0)
			(effects
				(font
					(size 1.27 1.27)
				)
				(justify left bottom)
				(hide yes)
			)
		)
		(pin "1"
		)
		(pin "2"
		)
		(instances
			(project "jetson-agx-thor-baseboard"
				(path ""
					(reference "R233")
					(unit 1)
				)
			)
		)
	)
	(symbol
		(lib_id "antmicropower:GND")
		(at 58.42 38.1 0)
		(unit 1)
		(exclude_from_sim no)
		(in_bom yes)
		(on_board yes)
		(dnp no)
		(fields_autoplaced yes)
		(property "Reference" "#PWR0112"
			(at 58.42 44.45 0)
			(effects
				(font
					(size 1.27 1.27)
				)
				(justify left bottom)
				(hide yes)
			)
		)
		(property "Value" "GND"
			(at 58.42 41.91 0)
			(effects
				(font
					(size 1.27 1.27)
					(thickness 0.15)
				)
			)
		)
		(property "Footprint" ""
			(at 67.31 45.72 0)
			(effects
				(font
					(size 1.27 1.27)
					(thickness 0.15)
				)
				(justify left bottom)
				(hide yes)
			)
		)
		(property "Datasheet" ""
			(at 67.31 50.8 0)
			(effects
				(font
					(size 1.27 1.27)
					(thickness 0.15)
				)
				(justify left bottom)
				(hide yes)
			)
		)
		(property "Description" ""
			(at 58.42 38.1 0)
			(effects
				(font
					(size 1.27 1.27)
				)
				(hide yes)
			)
		)
		(property "Author" "Antmicro"
			(at 67.31 45.72 0)
			(effects
				(font
					(size 1.27 1.27)
					(thickness 0.15)
				)
				(justify left bottom)
				(hide yes)
			)
		)
		(property "License" "Apache-2.0"
			(at 67.31 48.26 0)
			(effects
				(font
					(size 1.27 1.27)
					(thickness 0.15)
				)
				(justify left bottom)
				(hide yes)
			)
		)
		(pin "1"
		)
		(instances
			(project "jetson-agx-thor-baseboard"
				(path ""
					(reference "#PWR0112")
					(unit 1)
				)
			)
		)
	)
	(symbol
		(lib_id "antmicroTestPoints:TP_0.75mm_SMD")
		(at 35.56 140.97 90)
		(unit 1)
		(exclude_from_sim no)
		(in_bom no)
		(on_board yes)
		(dnp no)
		(property "Reference" "TP90"
			(at 38.1 135.89 90)
			(effects
				(font
					(size 1.27 1.27)
					(thickness 0.15)
				)
				(justify left)
			)
		)
		(property "Value" "TP_0.75mm_SMD"
			(at 39.37 130.81 0)
			(effects
				(font
					(size 1.27 1.27)
					(thickness 0.15)
				)
				(justify left bottom)
				(hide yes)
			)
		)
		(property "Footprint" "antmicro-footprints:TP_SMD_0.75mm"
			(at 41.91 130.81 0)
			(effects
				(font
					(size 1.27 1.27)
					(thickness 0.15)
				)
				(justify left bottom)
				(hide yes)
			)
		)
		(property "Datasheet" ""
			(at 48.26 123.19 0)
			(effects
				(font
					(size 1.27 1.27)
					(thickness 0.15)
				)
				(justify left bottom)
				(hide yes)
			)
		)
		(property "Description" "SMT test point"
			(at 35.56 140.97 0)
			(effects
				(font
					(size 1.27 1.27)
				)
				(hide yes)
			)
		)
		(property "MPN" ""
			(at 46.99 130.175 0)
			(effects
				(font
					(size 1.27 1.27)
					(thickness 0.15)
				)
				(justify left bottom)
				(hide yes)
			)
		)
		(property "Manufacturer" ""
			(at 41.91 130.175 0)
			(effects
				(font
					(size 1.27 1.27)
					(thickness 0.15)
				)
				(justify left bottom)
				(hide yes)
			)
		)
		(property "Author" "Antmicro"
			(at 44.45 130.81 0)
			(effects
				(font
					(size 1.27 1.27)
					(thickness 0.15)
				)
				(justify left bottom)
				(hide yes)
			)
		)
		(property "License" "Apache-2.0"
			(at 46.99 130.81 0)
			(effects
				(font
					(size 1.27 1.27)
					(thickness 0.15)
				)
				(justify left bottom)
				(hide yes)
			)
		)
		(pin "1"
		)
		(instances
			(project "jetson-agx-thor-baseboard"
				(path ""
					(reference "TP90")
					(unit 1)
				)
			)
		)
	)
	(symbol
		(lib_id "antmicroResistors0402:R_10k_0402")
		(at 185.42 44.45 90)
		(unit 1)
		(exclude_from_sim no)
		(in_bom yes)
		(on_board yes)
		(dnp no)
		(property "Reference" "R235"
			(at 186.69 40.64 90)
			(effects
				(font
					(size 1.27 1.27)
				)
				(justify right)
			)
		)
		(property "Value" "R_10k_0402"
			(at 198.12 24.13 0)
			(effects
				(font
					(size 1.27 1.27)
					(thickness 0.15)
				)
				(justify left bottom)
				(hide yes)
			)
		)
		(property "Footprint" "antmicro-footprints:R_0402_1005Metric"
			(at 200.66 24.13 0)
			(effects
				(font
					(size 1.27 1.27)
					(thickness 0.15)
				)
				(justify left bottom)
				(hide yes)
			)
		)
		(property "Datasheet" "https://www.bourns.com/docs/product-datasheets/cr.pdf"
			(at 203.2 24.13 0)
			(effects
				(font
					(size 1.27 1.27)
					(thickness 0.15)
				)
				(justify left bottom)
				(hide yes)
			)
		)
		(property "Description" "SMD Chip Resistor, 10 kohm, ± 1%, 62.5 mW, 0402 [1005 Metric], Thick Film, General Purpose"
			(at 185.42 44.45 0)
			(effects
				(font
					(size 1.27 1.27)
				)
				(hide yes)
			)
		)
		(property "Manufacturer" "Bourns"
			(at 208.28 24.13 0)
			(effects
				(font
					(size 1.27 1.27)
					(thickness 0.15)
				)
				(justify left bottom)
				(hide yes)
			)
		)
		(property "MPN" "CR0402-FX-1002GLF"
			(at 205.74 24.13 0)
			(effects
				(font
					(size 1.27 1.27)
					(thickness 0.15)
				)
				(justify left bottom)
				(hide yes)
			)
		)
		(property "Val" "10k"
			(at 186.69 43.18 90)
			(effects
				(font
					(size 1.27 1.27)
					(thickness 0.15)
				)
				(justify right)
			)
		)
		(property "License" "Apache-2.0"
			(at 210.82 24.13 0)
			(effects
				(font
					(size 1.27 1.27)
					(thickness 0.15)
				)
				(justify left bottom)
				(hide yes)
			)
		)
		(property "Author" "Antmicro"
			(at 213.36 24.13 0)
			(effects
				(font
					(size 1.27 1.27)
					(thickness 0.15)
				)
				(justify left bottom)
				(hide yes)
			)
		)
		(property "Tolerance" "1%"
			(at 195.58 24.13 0)
			(effects
				(font
					(size 1.27 1.27)
				)
				(justify left bottom)
				(hide yes)
			)
		)
		(pin "1"
		)
		(pin "2"
		)
		(instances
			(project "jetson-agx-thor-baseboard"
				(path ""
					(reference "R235")
					(unit 1)
				)
			)
		)
	)
	(symbol
		(lib_id "antmicroCapacitors0402:C_10u_0402")
		(at 48.26 36.83 90)
		(unit 1)
		(exclude_from_sim no)
		(in_bom yes)
		(on_board yes)
		(dnp no)
		(property "Reference" "C207"
			(at 50.038 33.02 90)
			(effects
				(font
					(size 1.27 1.27)
					(thickness 0.15)
				)
				(justify right)
			)
		)
		(property "Value" "C_10u_0402"
			(at 58.42 16.51 0)
			(effects
				(font
					(size 1.27 1.27)
					(thickness 0.15)
				)
				(justify left bottom)
				(hide yes)
			)
		)
		(property "Footprint" "antmicro-footprints:C_0402_1005Metric"
			(at 60.96 16.51 0)
			(effects
				(font
					(size 1.27 1.27)
					(thickness 0.15)
				)
				(justify left bottom)
				(hide yes)
			)
		)
		(property "Datasheet" "https://www.yageo.com/en/Chart/Download/pdf/CC0402MRX5R5BB106"
			(at 63.5 16.51 0)
			(effects
				(font
					(size 1.27 1.27)
					(thickness 0.15)
				)
				(justify left bottom)
				(hide yes)
			)
		)
		(property "Description" "SMD Multilayer Ceramic Capacitor, 10 µF, 6.3 V, 0402 [1005 Metric], ± 20%, X5R, CC Series"
			(at 48.26 36.83 0)
			(effects
				(font
					(size 1.27 1.27)
				)
				(hide yes)
			)
		)
		(property "MPN" "CC0402MRX5R5BB106"
			(at 66.04 16.51 0)
			(effects
				(font
					(size 1.27 1.27)
					(thickness 0.15)
				)
				(justify left bottom)
				(hide yes)
			)
		)
		(property "Manufacturer" "YAGEO"
			(at 68.58 16.51 0)
			(effects
				(font
					(size 1.27 1.27)
					(thickness 0.15)
				)
				(justify left bottom)
				(hide yes)
			)
		)
		(property "License" "Apache-2.0"
			(at 71.12 16.51 0)
			(effects
				(font
					(size 1.27 1.27)
					(thickness 0.15)
				)
				(justify left bottom)
				(hide yes)
			)
		)
		(property "Author" "Antmicro"
			(at 73.66 16.51 0)
			(effects
				(font
					(size 1.27 1.27)
					(thickness 0.15)
				)
				(justify left bottom)
				(hide yes)
			)
		)
		(property "Val" "10u"
			(at 50.038 35.56 90)
			(effects
				(font
					(size 1.27 1.27)
					(thickness 0.15)
				)
				(justify right)
			)
		)
		(property "Voltage" "16V"
			(at 76.2 16.51 0)
			(effects
				(font
					(size 1.27 1.27)
				)
				(justify left bottom)
				(hide yes)
			)
		)
		(property "Dielectric" ""
			(at 78.74 16.51 0)
			(effects
				(font
					(size 1.27 1.27)
				)
				(justify left bottom)
				(hide yes)
			)
		)
		(pin "2"
		)
		(pin "1"
		)
		(instances
			(project "jetson-agx-thor-baseboard"
				(path ""
					(reference "C207")
					(unit 1)
				)
			)
		)
	)
	(symbol
		(lib_id "antmicroResistors0402:R_10k_0402")
		(at 204.47 236.22 90)
		(unit 1)
		(exclude_from_sim no)
		(in_bom yes)
		(on_board yes)
		(dnp no)
		(fields_autoplaced yes)
		(property "Reference" "R238"
			(at 206.502 232.41 90)
			(effects
				(font
					(size 1.27 1.27)
				)
				(justify right)
			)
		)
		(property "Value" "R_10k_0402"
			(at 217.17 215.9 0)
			(effects
				(font
					(size 1.27 1.27)
					(thickness 0.15)
				)
				(justify left bottom)
				(hide yes)
			)
		)
		(property "Footprint" "antmicro-footprints:R_0402_1005Metric"
			(at 219.71 215.9 0)
			(effects
				(font
					(size 1.27 1.27)
					(thickness 0.15)
				)
				(justify left bottom)
				(hide yes)
			)
		)
		(property "Datasheet" "https://www.bourns.com/docs/product-datasheets/cr.pdf"
			(at 222.25 215.9 0)
			(effects
				(font
					(size 1.27 1.27)
					(thickness 0.15)
				)
				(justify left bottom)
				(hide yes)
			)
		)
		(property "Description" "SMD Chip Resistor, 10 kohm, ± 1%, 62.5 mW, 0402 [1005 Metric], Thick Film, General Purpose"
			(at 204.47 236.22 0)
			(effects
				(font
					(size 1.27 1.27)
				)
				(hide yes)
			)
		)
		(property "Manufacturer" "Bourns"
			(at 227.33 215.9 0)
			(effects
				(font
					(size 1.27 1.27)
					(thickness 0.15)
				)
				(justify left bottom)
				(hide yes)
			)
		)
		(property "MPN" "CR0402-FX-1002GLF"
			(at 224.79 215.9 0)
			(effects
				(font
					(size 1.27 1.27)
					(thickness 0.15)
				)
				(justify left bottom)
				(hide yes)
			)
		)
		(property "Val" "10k"
			(at 206.502 234.95 90)
			(effects
				(font
					(size 1.27 1.27)
					(thickness 0.15)
				)
				(justify right)
			)
		)
		(property "License" "Apache-2.0"
			(at 229.87 215.9 0)
			(effects
				(font
					(size 1.27 1.27)
					(thickness 0.15)
				)
				(justify left bottom)
				(hide yes)
			)
		)
		(property "Author" "Antmicro"
			(at 232.41 215.9 0)
			(effects
				(font
					(size 1.27 1.27)
					(thickness 0.15)
				)
				(justify left bottom)
				(hide yes)
			)
		)
		(property "Tolerance" "1%"
			(at 214.63 215.9 0)
			(effects
				(font
					(size 1.27 1.27)
				)
				(justify left bottom)
				(hide yes)
			)
		)
		(pin "1"
		)
		(pin "2"
		)
		(instances
			(project "jetson-agx-thor-baseboard"
				(path ""
					(reference "R238")
					(unit 1)
				)
			)
		)
	)
	(symbol
		(lib_id "antmicropower:GND")
		(at 279.4 62.23 0)
		(unit 1)
		(exclude_from_sim no)
		(in_bom yes)
		(on_board yes)
		(dnp no)
		(fields_autoplaced yes)
		(property "Reference" "#PWR0420"
			(at 279.4 68.58 0)
			(effects
				(font
					(size 1.27 1.27)
				)
				(justify left bottom)
				(hide yes)
			)
		)
		(property "Value" "GND"
			(at 279.4 66.04 0)
			(effects
				(font
					(size 1.27 1.27)
					(thickness 0.15)
				)
			)
		)
		(property "Footprint" ""
			(at 288.29 69.85 0)
			(effects
				(font
					(size 1.27 1.27)
					(thickness 0.15)
				)
				(justify left bottom)
				(hide yes)
			)
		)
		(property "Datasheet" ""
			(at 288.29 74.93 0)
			(effects
				(font
					(size 1.27 1.27)
					(thickness 0.15)
				)
				(justify left bottom)
				(hide yes)
			)
		)
		(property "Description" ""
			(at 279.4 62.23 0)
			(effects
				(font
					(size 1.27 1.27)
				)
				(hide yes)
			)
		)
		(property "Author" "Antmicro"
			(at 288.29 69.85 0)
			(effects
				(font
					(size 1.27 1.27)
					(thickness 0.15)
				)
				(justify left bottom)
				(hide yes)
			)
		)
		(property "License" "Apache-2.0"
			(at 288.29 72.39 0)
			(effects
				(font
					(size 1.27 1.27)
					(thickness 0.15)
				)
				(justify left bottom)
				(hide yes)
			)
		)
		(pin "1"
		)
		(instances
			(project "jetson-agx-thor-baseboard"
				(path ""
					(reference "#PWR0420")
					(unit 1)
				)
			)
		)
	)
	(symbol
		(lib_id "antmicroTestPoints:TP_0.75mm_SMD")
		(at 194.31 138.43 90)
		(unit 1)
		(exclude_from_sim no)
		(in_bom no)
		(on_board yes)
		(dnp no)
		(property "Reference" "TP88"
			(at 197.358 133.35 90)
			(effects
				(font
					(size 1.27 1.27)
					(thickness 0.15)
				)
				(justify left)
			)
		)
		(property "Value" "TP_0.75mm_SMD"
			(at 198.12 128.27 0)
			(effects
				(font
					(size 1.27 1.27)
					(thickness 0.15)
				)
				(justify left bottom)
				(hide yes)
			)
		)
		(property "Footprint" "antmicro-footprints:TP_SMD_0.75mm"
			(at 200.66 128.27 0)
			(effects
				(font
					(size 1.27 1.27)
					(thickness 0.15)
				)
				(justify left bottom)
				(hide yes)
			)
		)
		(property "Datasheet" ""
			(at 207.01 120.65 0)
			(effects
				(font
					(size 1.27 1.27)
					(thickness 0.15)
				)
				(justify left bottom)
				(hide yes)
			)
		)
		(property "Description" "SMT test point"
			(at 194.31 138.43 0)
			(effects
				(font
					(size 1.27 1.27)
				)
				(hide yes)
			)
		)
		(property "MPN" ""
			(at 205.74 127.635 0)
			(effects
				(font
					(size 1.27 1.27)
					(thickness 0.15)
				)
				(justify left bottom)
				(hide yes)
			)
		)
		(property "Manufacturer" ""
			(at 200.66 127.635 0)
			(effects
				(font
					(size 1.27 1.27)
					(thickness 0.15)
				)
				(justify left bottom)
				(hide yes)
			)
		)
		(property "Author" "Antmicro"
			(at 203.2 128.27 0)
			(effects
				(font
					(size 1.27 1.27)
					(thickness 0.15)
				)
				(justify left bottom)
				(hide yes)
			)
		)
		(property "License" "Apache-2.0"
			(at 205.74 128.27 0)
			(effects
				(font
					(size 1.27 1.27)
					(thickness 0.15)
				)
				(justify left bottom)
				(hide yes)
			)
		)
		(pin "1"
		)
		(instances
			(project "jetson-agx-thor-baseboard"
				(path ""
					(reference "TP88")
					(unit 1)
				)
			)
		)
	)
	(symbol
		(lib_id "antmicroCapacitors0402:C_100n_0402")
		(at 40.64 132.08 270)
		(mirror x)
		(unit 1)
		(exclude_from_sim no)
		(in_bom yes)
		(on_board yes)
		(dnp no)
		(property "Reference" "C202"
			(at 38.735 128.27 90)
			(effects
				(font
					(size 1.27 1.27)
				)
				(justify right)
			)
		)
		(property "Value" "C_100n_0402"
			(at 30.48 111.76 0)
			(effects
				(font
					(size 1.27 1.27)
					(thickness 0.15)
				)
				(justify left bottom)
				(hide yes)
			)
		)
		(property "Footprint" "antmicro-footprints:C_0402_1005Metric"
			(at 27.94 111.76 0)
			(effects
				(font
					(size 1.27 1.27)
					(thickness 0.15)
				)
				(justify left bottom)
				(hide yes)
			)
		)
		(property "Datasheet" "https://www.murata.com/products/productdetail?partno=GRM155R61H104KE14%23"
			(at 25.4 111.76 0)
			(effects
				(font
					(size 1.27 1.27)
					(thickness 0.15)
				)
				(justify left bottom)
				(hide yes)
			)
		)
		(property "Description" "SMD Multilayer Ceramic Capacitor, 0.1 µF, 50 V, 0402 [1005 Metric], ± 10%, X5R, GRM Series"
			(at 40.64 132.08 0)
			(effects
				(font
					(size 1.27 1.27)
				)
				(hide yes)
			)
		)
		(property "Manufacturer" "Murata"
			(at 20.32 111.76 0)
			(effects
				(font
					(size 1.27 1.27)
					(thickness 0.15)
				)
				(justify left bottom)
				(hide yes)
			)
		)
		(property "MPN" "GRM155R61H104KE14D"
			(at 22.86 111.76 0)
			(effects
				(font
					(size 1.27 1.27)
					(thickness 0.15)
				)
				(justify left bottom)
				(hide yes)
			)
		)
		(property "Val" "100n"
			(at 38.735 130.81 90)
			(effects
				(font
					(size 1.27 1.27)
					(thickness 0.15)
				)
				(justify right)
			)
		)
		(property "License" "Apache-2.0"
			(at 17.78 111.76 0)
			(effects
				(font
					(size 1.27 1.27)
					(thickness 0.15)
				)
				(justify left bottom)
				(hide yes)
			)
		)
		(property "Author" "Antmicro"
			(at 15.24 111.76 0)
			(effects
				(font
					(size 1.27 1.27)
					(thickness 0.15)
				)
				(justify left bottom)
				(hide yes)
			)
		)
		(property "Voltage" "50V"
			(at 12.7 111.76 0)
			(effects
				(font
					(size 1.27 1.27)
				)
				(justify left bottom)
				(hide yes)
			)
		)
		(property "Dielectric" "X5R"
			(at 10.16 111.76 0)
			(effects
				(font
					(size 1.27 1.27)
				)
				(justify left bottom)
				(hide yes)
			)
		)
		(pin "1"
		)
		(pin "2"
		)
		(instances
			(project "jetson-agx-thor-baseboard"
				(path ""
					(reference "C202")
					(unit 1)
				)
			)
		)
	)
	(symbol
		(lib_id "antmicropower:GND")
		(at 40.64 134.62 0)
		(unit 1)
		(exclude_from_sim no)
		(in_bom yes)
		(on_board yes)
		(dnp no)
		(fields_autoplaced yes)
		(property "Reference" "#PWR0385"
			(at 40.64 140.97 0)
			(effects
				(font
					(size 1.27 1.27)
				)
				(justify left bottom)
				(hide yes)
			)
		)
		(property "Value" "GND"
			(at 40.64 138.43 0)
			(effects
				(font
					(size 1.27 1.27)
					(thickness 0.15)
				)
			)
		)
		(property "Footprint" ""
			(at 49.53 142.24 0)
			(effects
				(font
					(size 1.27 1.27)
					(thickness 0.15)
				)
				(justify left bottom)
				(hide yes)
			)
		)
		(property "Datasheet" ""
			(at 49.53 147.32 0)
			(effects
				(font
					(size 1.27 1.27)
					(thickness 0.15)
				)
				(justify left bottom)
				(hide yes)
			)
		)
		(property "Description" ""
			(at 40.64 134.62 0)
			(effects
				(font
					(size 1.27 1.27)
				)
				(hide yes)
			)
		)
		(property "Author" "Antmicro"
			(at 49.53 142.24 0)
			(effects
				(font
					(size 1.27 1.27)
					(thickness 0.15)
				)
				(justify left bottom)
				(hide yes)
			)
		)
		(property "License" "Apache-2.0"
			(at 49.53 144.78 0)
			(effects
				(font
					(size 1.27 1.27)
					(thickness 0.15)
				)
				(justify left bottom)
				(hide yes)
			)
		)
		(pin "1"
		)
		(instances
			(project "jetson-agx-thor-baseboard"
				(path ""
					(reference "#PWR0385")
					(unit 1)
				)
			)
		)
	)
	(symbol
		(lib_id "antmicropower:+1V8")
		(at 204.47 200.66 0)
		(unit 1)
		(exclude_from_sim no)
		(in_bom yes)
		(on_board yes)
		(dnp no)
		(property "Reference" "#PWR0404"
			(at 204.47 204.47 0)
			(effects
				(font
					(size 1.27 1.27)
				)
				(justify left bottom)
				(hide yes)
			)
		)
		(property "Value" "+1V8"
			(at 201.295 196.85 0)
			(effects
				(font
					(size 1.27 1.27)
					(thickness 0.15)
				)
				(justify left)
			)
		)
		(property "Footprint" ""
			(at 219.71 208.28 0)
			(effects
				(font
					(size 1.27 1.27)
					(thickness 0.15)
				)
				(justify left bottom)
				(hide yes)
			)
		)
		(property "Datasheet" ""
			(at 219.71 210.82 0)
			(effects
				(font
					(size 1.27 1.27)
					(thickness 0.15)
				)
				(justify left bottom)
				(hide yes)
			)
		)
		(property "Description" ""
			(at 204.47 200.66 0)
			(effects
				(font
					(size 1.27 1.27)
				)
				(hide yes)
			)
		)
		(property "Author" "Antmicro"
			(at 219.71 205.74 0)
			(effects
				(font
					(size 1.27 1.27)
					(thickness 0.15)
				)
				(justify left bottom)
				(hide yes)
			)
		)
		(property "License" "Apache-2.0"
			(at 219.71 208.28 0)
			(effects
				(font
					(size 1.27 1.27)
					(thickness 0.15)
				)
				(justify left bottom)
				(hide yes)
			)
		)
		(pin "1"
		)
		(instances
			(project "jetson-agx-thor-baseboard"
				(path ""
					(reference "#PWR0404")
					(unit 1)
				)
			)
		)
	)
	(symbol
		(lib_id "antmicropower:+3V3")
		(at 78.74 69.85 0)
		(unit 1)
		(exclude_from_sim no)
		(in_bom yes)
		(on_board yes)
		(dnp no)
		(property "Reference" "#PWR0389"
			(at 93.98 69.85 0)
			(effects
				(font
					(size 1.27 1.27)
					(thickness 0.15)
				)
				(justify left bottom)
				(hide yes)
			)
		)
		(property "Value" "+3V3"
			(at 81.788 68.326 0)
			(effects
				(font
					(size 1.27 1.27)
					(thickness 0.15)
				)
			)
		)
		(property "Footprint" ""
			(at 93.98 77.47 0)
			(effects
				(font
					(size 1.27 1.27)
					(thickness 0.15)
				)
				(justify left bottom)
				(hide yes)
			)
		)
		(property "Datasheet" ""
			(at 93.98 80.01 0)
			(effects
				(font
					(size 1.27 1.27)
					(thickness 0.15)
				)
				(justify left bottom)
				(hide yes)
			)
		)
		(property "Description" ""
			(at 78.74 69.85 0)
			(effects
				(font
					(size 1.27 1.27)
				)
				(hide yes)
			)
		)
		(property "Author" "Antmicro"
			(at 93.98 72.39 0)
			(effects
				(font
					(size 1.27 1.27)
					(thickness 0.15)
				)
				(justify left bottom)
				(hide yes)
			)
		)
		(property "License" "Apache-2.0"
			(at 93.98 74.93 0)
			(effects
				(font
					(size 1.27 1.27)
					(thickness 0.15)
				)
				(justify left bottom)
				(hide yes)
			)
		)
		(pin "1"
		)
		(instances
			(project "jetson-agx-thor-baseboard"
				(path ""
					(reference "#PWR0389")
					(unit 1)
				)
			)
		)
	)
	(symbol
		(lib_id "antmicropower:+3V3")
		(at 48.26 30.48 0)
		(unit 1)
		(exclude_from_sim no)
		(in_bom yes)
		(on_board yes)
		(dnp no)
		(property "Reference" "#PWR0386"
			(at 48.26 34.29 0)
			(effects
				(font
					(size 1.27 1.27)
				)
				(justify left bottom)
				(hide yes)
			)
		)
		(property "Value" "+3V3"
			(at 45.085 26.67 0)
			(effects
				(font
					(size 1.27 1.27)
					(thickness 0.15)
				)
				(justify left)
			)
		)
		(property "Footprint" ""
			(at 63.5 38.1 0)
			(effects
				(font
					(size 1.27 1.27)
					(thickness 0.15)
				)
				(justify left bottom)
				(hide yes)
			)
		)
		(property "Datasheet" ""
			(at 63.5 40.64 0)
			(effects
				(font
					(size 1.27 1.27)
					(thickness 0.15)
				)
				(justify left bottom)
				(hide yes)
			)
		)
		(property "Description" ""
			(at 48.26 30.48 0)
			(effects
				(font
					(size 1.27 1.27)
				)
				(hide yes)
			)
		)
		(property "Author" "Antmicro"
			(at 63.5 33.02 0)
			(effects
				(font
					(size 1.27 1.27)
					(thickness 0.15)
				)
				(justify left bottom)
				(hide yes)
			)
		)
		(property "License" "Apache-2.0"
			(at 63.5 35.56 0)
			(effects
				(font
					(size 1.27 1.27)
					(thickness 0.15)
				)
				(justify left bottom)
				(hide yes)
			)
		)
		(pin "1"
		)
		(instances
			(project "jetson-agx-thor-baseboard"
				(path ""
					(reference "#PWR0386")
					(unit 1)
				)
			)
		)
	)
	(symbol
		(lib_id "antmicropower:GND")
		(at 232.41 147.32 0)
		(unit 1)
		(exclude_from_sim no)
		(in_bom yes)
		(on_board yes)
		(dnp no)
		(fields_autoplaced yes)
		(property "Reference" "#PWR0415"
			(at 232.41 153.67 0)
			(effects
				(font
					(size 1.27 1.27)
				)
				(justify left bottom)
				(hide yes)
			)
		)
		(property "Value" "GND"
			(at 232.41 151.13 0)
			(effects
				(font
					(size 1.27 1.27)
					(thickness 0.15)
				)
			)
		)
		(property "Footprint" ""
			(at 241.3 154.94 0)
			(effects
				(font
					(size 1.27 1.27)
					(thickness 0.15)
				)
				(justify left bottom)
				(hide yes)
			)
		)
		(property "Datasheet" ""
			(at 241.3 160.02 0)
			(effects
				(font
					(size 1.27 1.27)
					(thickness 0.15)
				)
				(justify left bottom)
				(hide yes)
			)
		)
		(property "Description" ""
			(at 232.41 147.32 0)
			(effects
				(font
					(size 1.27 1.27)
				)
				(hide yes)
			)
		)
		(property "Author" "Antmicro"
			(at 241.3 154.94 0)
			(effects
				(font
					(size 1.27 1.27)
					(thickness 0.15)
				)
				(justify left bottom)
				(hide yes)
			)
		)
		(property "License" "Apache-2.0"
			(at 241.3 157.48 0)
			(effects
				(font
					(size 1.27 1.27)
					(thickness 0.15)
				)
				(justify left bottom)
				(hide yes)
			)
		)
		(pin "1"
		)
		(instances
			(project "jetson-agx-thor-baseboard"
				(path ""
					(reference "#PWR0415")
					(unit 1)
				)
			)
		)
	)
	(symbol
		(lib_id "antmicropower:GND")
		(at 217.17 59.69 0)
		(unit 1)
		(exclude_from_sim no)
		(in_bom yes)
		(on_board yes)
		(dnp no)
		(fields_autoplaced yes)
		(property "Reference" "#PWR0413"
			(at 217.17 66.04 0)
			(effects
				(font
					(size 1.27 1.27)
				)
				(justify left bottom)
				(hide yes)
			)
		)
		(property "Value" "GND"
			(at 217.17 63.5 0)
			(effects
				(font
					(size 1.27 1.27)
					(thickness 0.15)
				)
			)
		)
		(property "Footprint" ""
			(at 226.06 67.31 0)
			(effects
				(font
					(size 1.27 1.27)
					(thickness 0.15)
				)
				(justify left bottom)
				(hide yes)
			)
		)
		(property "Datasheet" ""
			(at 226.06 72.39 0)
			(effects
				(font
					(size 1.27 1.27)
					(thickness 0.15)
				)
				(justify left bottom)
				(hide yes)
			)
		)
		(property "Description" ""
			(at 217.17 59.69 0)
			(effects
				(font
					(size 1.27 1.27)
				)
				(hide yes)
			)
		)
		(property "Author" "Antmicro"
			(at 226.06 67.31 0)
			(effects
				(font
					(size 1.27 1.27)
					(thickness 0.15)
				)
				(justify left bottom)
				(hide yes)
			)
		)
		(property "License" "Apache-2.0"
			(at 226.06 69.85 0)
			(effects
				(font
					(size 1.27 1.27)
					(thickness 0.15)
				)
				(justify left bottom)
				(hide yes)
			)
		)
		(pin "1"
		)
		(instances
			(project "jetson-agx-thor-baseboard"
				(path ""
					(reference "#PWR0413")
					(unit 1)
				)
			)
		)
	)
	(symbol
		(lib_id "antmicroTestPoints:TP_0.75mm_SMD")
		(at 237.49 49.53 90)
		(unit 1)
		(exclude_from_sim no)
		(in_bom no)
		(on_board yes)
		(dnp no)
		(property "Reference" "TP93"
			(at 239.522 43.942 90)
			(effects
				(font
					(size 1.27 1.27)
					(thickness 0.15)
				)
				(justify left)
			)
		)
		(property "Value" "TP_0.75mm_SMD"
			(at 241.3 39.37 0)
			(effects
				(font
					(size 1.27 1.27)
					(thickness 0.15)
				)
				(justify left bottom)
				(hide yes)
			)
		)
		(property "Footprint" "antmicro-footprints:TP_SMD_0.75mm"
			(at 243.84 39.37 0)
			(effects
				(font
					(size 1.27 1.27)
					(thickness 0.15)
				)
				(justify left bottom)
				(hide yes)
			)
		)
		(property "Datasheet" ""
			(at 250.19 31.75 0)
			(effects
				(font
					(size 1.27 1.27)
					(thickness 0.15)
				)
				(justify left bottom)
				(hide yes)
			)
		)
		(property "Description" "SMT test point"
			(at 237.49 49.53 0)
			(effects
				(font
					(size 1.27 1.27)
				)
				(hide yes)
			)
		)
		(property "MPN" ""
			(at 248.92 38.735 0)
			(effects
				(font
					(size 1.27 1.27)
					(thickness 0.15)
				)
				(justify left bottom)
				(hide yes)
			)
		)
		(property "Manufacturer" ""
			(at 243.84 38.735 0)
			(effects
				(font
					(size 1.27 1.27)
					(thickness 0.15)
				)
				(justify left bottom)
				(hide yes)
			)
		)
		(property "Author" "Antmicro"
			(at 246.38 39.37 0)
			(effects
				(font
					(size 1.27 1.27)
					(thickness 0.15)
				)
				(justify left bottom)
				(hide yes)
			)
		)
		(property "License" "Apache-2.0"
			(at 248.92 39.37 0)
			(effects
				(font
					(size 1.27 1.27)
					(thickness 0.15)
				)
				(justify left bottom)
				(hide yes)
			)
		)
		(pin "1"
		)
		(instances
			(project "jetson-agx-thor-baseboard"
				(path ""
					(reference "TP93")
					(unit 1)
				)
			)
		)
	)
	(symbol
		(lib_id "antmicroTVSDiodes:TPD4E05U06QDQARQ1")
		(at 229.87 88.9 270)
		(unit 1)
		(exclude_from_sim no)
		(in_bom yes)
		(on_board yes)
		(dnp no)
		(property "Reference" "U67"
			(at 217.932 99.06 90)
			(effects
				(font
					(size 1.27 1.27)
				)
				(justify left)
			)
		)
		(property "Value" "TPD4E05U06QDQARQ1"
			(at 219.71 113.03 0)
			(effects
				(font
					(size 1.27 1.27)
					(thickness 0.15)
				)
				(justify left bottom)
				(hide yes)
			)
		)
		(property "Footprint" "antmicro-footprints:USON-10_2.5x1mm_P0.5mm"
			(at 224.79 113.03 0)
			(effects
				(font
					(size 1.27 1.27)
					(thickness 0.15)
				)
				(justify left bottom)
				(hide yes)
			)
		)
		(property "Datasheet" "https://www.ti.com/lit/ds/symlink/tpd4e05u06-q1.pdf?HQS=dis-mous-null-mousermode-dsf-pf-null-wwe&ts=1663591265741&ref_url=https%253A%252F%252Fwww.mouser.com%252F"
			(at 222.25 113.03 0)
			(effects
				(font
					(size 1.27 1.27)
					(thickness 0.15)
				)
				(justify left bottom)
				(hide yes)
			)
		)
		(property "Description" "TVS diode array, 12 kV, USON-10, 5.5 V, 0.5 pF"
			(at 229.87 88.9 0)
			(effects
				(font
					(size 1.27 1.27)
				)
				(hide yes)
			)
		)
		(property "Manufacturer" "Texas Instruments"
			(at 217.17 113.03 0)
			(effects
				(font
					(size 1.27 1.27)
					(thickness 0.15)
				)
				(justify left bottom)
				(hide yes)
			)
		)
		(property "MPN" "TPD4E05U06QDQARQ1"
			(at 217.932 101.346 90)
			(effects
				(font
					(size 1.27 1.27)
					(thickness 0.15)
				)
				(justify left)
			)
		)
		(property "Author" "Antmicro"
			(at 214.63 113.03 0)
			(effects
				(font
					(size 1.27 1.27)
					(thickness 0.15)
				)
				(justify left bottom)
				(hide yes)
			)
		)
		(property "License" "Apache-2.0"
			(at 212.09 113.03 0)
			(effects
				(font
					(size 1.27 1.27)
					(thickness 0.15)
				)
				(justify left bottom)
				(hide yes)
			)
		)
		(pin "1"
		)
		(pin "10"
		)
		(pin "2"
		)
		(pin "3"
		)
		(pin "4"
		)
		(pin "5"
		)
		(pin "6"
		)
		(pin "7"
		)
		(pin "8"
		)
		(pin "9"
		)
		(instances
			(project "jetson-agx-thor-baseboard"
				(path ""
					(reference "U67")
					(unit 1)
				)
			)
		)
	)
	(symbol
		(lib_id "antmicropower:GND")
		(at 190.5 62.23 0)
		(unit 1)
		(exclude_from_sim no)
		(in_bom yes)
		(on_board yes)
		(dnp no)
		(fields_autoplaced yes)
		(property "Reference" "#PWR0403"
			(at 190.5 68.58 0)
			(effects
				(font
					(size 1.27 1.27)
				)
				(justify left bottom)
				(hide yes)
			)
		)
		(property "Value" "GND"
			(at 190.5 66.04 0)
			(effects
				(font
					(size 1.27 1.27)
					(thickness 0.15)
				)
			)
		)
		(property "Footprint" ""
			(at 199.39 69.85 0)
			(effects
				(font
					(size 1.27 1.27)
					(thickness 0.15)
				)
				(justify left bottom)
				(hide yes)
			)
		)
		(property "Datasheet" ""
			(at 199.39 74.93 0)
			(effects
				(font
					(size 1.27 1.27)
					(thickness 0.15)
				)
				(justify left bottom)
				(hide yes)
			)
		)
		(property "Description" ""
			(at 190.5 62.23 0)
			(effects
				(font
					(size 1.27 1.27)
				)
				(hide yes)
			)
		)
		(property "Author" "Antmicro"
			(at 199.39 69.85 0)
			(effects
				(font
					(size 1.27 1.27)
					(thickness 0.15)
				)
				(justify left bottom)
				(hide yes)
			)
		)
		(property "License" "Apache-2.0"
			(at 199.39 72.39 0)
			(effects
				(font
					(size 1.27 1.27)
					(thickness 0.15)
				)
				(justify left bottom)
				(hide yes)
			)
		)
		(pin "1"
		)
		(instances
			(project "jetson-agx-thor-baseboard"
				(path ""
					(reference "#PWR0403")
					(unit 1)
				)
			)
		)
	)
	(symbol
		(lib_id "antmicropower:GND")
		(at 328.93 86.36 0)
		(unit 1)
		(exclude_from_sim no)
		(in_bom yes)
		(on_board yes)
		(dnp no)
		(fields_autoplaced yes)
		(property "Reference" "#PWR0426"
			(at 328.93 92.71 0)
			(effects
				(font
					(size 1.27 1.27)
				)
				(justify left bottom)
				(hide yes)
			)
		)
		(property "Value" "GND"
			(at 328.93 90.17 0)
			(effects
				(font
					(size 1.27 1.27)
					(thickness 0.15)
				)
			)
		)
		(property "Footprint" ""
			(at 337.82 93.98 0)
			(effects
				(font
					(size 1.27 1.27)
					(thickness 0.15)
				)
				(justify left bottom)
				(hide yes)
			)
		)
		(property "Datasheet" ""
			(at 337.82 99.06 0)
			(effects
				(font
					(size 1.27 1.27)
					(thickness 0.15)
				)
				(justify left bottom)
				(hide yes)
			)
		)
		(property "Description" ""
			(at 328.93 86.36 0)
			(effects
				(font
					(size 1.27 1.27)
				)
				(hide yes)
			)
		)
		(property "Author" "Antmicro"
			(at 337.82 93.98 0)
			(effects
				(font
					(size 1.27 1.27)
					(thickness 0.15)
				)
				(justify left bottom)
				(hide yes)
			)
		)
		(property "License" "Apache-2.0"
			(at 337.82 96.52 0)
			(effects
				(font
					(size 1.27 1.27)
					(thickness 0.15)
				)
				(justify left bottom)
				(hide yes)
			)
		)
		(pin "1"
		)
		(instances
			(project "jetson-agx-thor-baseboard"
				(path ""
					(reference "#PWR0426")
					(unit 1)
				)
			)
		)
	)
	(symbol
		(lib_id "antmicroTestPoints:TP_0.75mm_SMD")
		(at 370.84 144.78 0)
		(unit 1)
		(exclude_from_sim no)
		(in_bom no)
		(on_board yes)
		(dnp no)
		(property "Reference" "TP97"
			(at 374.904 144.78 0)
			(effects
				(font
					(size 1.27 1.27)
					(thickness 0.15)
				)
				(justify left)
			)
		)
		(property "Value" "TP_0.75mm_SMD"
			(at 381 148.59 0)
			(effects
				(font
					(size 1.27 1.27)
					(thickness 0.15)
				)
				(justify left bottom)
				(hide yes)
			)
		)
		(property "Footprint" "antmicro-footprints:TP_SMD_0.75mm"
			(at 381 151.13 0)
			(effects
				(font
					(size 1.27 1.27)
					(thickness 0.15)
				)
				(justify left bottom)
				(hide yes)
			)
		)
		(property "Datasheet" ""
			(at 388.62 157.48 0)
			(effects
				(font
					(size 1.27 1.27)
					(thickness 0.15)
				)
				(justify left bottom)
				(hide yes)
			)
		)
		(property "Description" "SMT test point"
			(at 370.84 144.78 0)
			(effects
				(font
					(size 1.27 1.27)
				)
				(hide yes)
			)
		)
		(property "MPN" ""
			(at 381.635 156.21 0)
			(effects
				(font
					(size 1.27 1.27)
					(thickness 0.15)
				)
				(justify left bottom)
				(hide yes)
			)
		)
		(property "Manufacturer" ""
			(at 381.635 151.13 0)
			(effects
				(font
					(size 1.27 1.27)
					(thickness 0.15)
				)
				(justify left bottom)
				(hide yes)
			)
		)
		(property "Author" "Antmicro"
			(at 381 153.67 0)
			(effects
				(font
					(size 1.27 1.27)
					(thickness 0.15)
				)
				(justify left bottom)
				(hide yes)
			)
		)
		(property "License" "Apache-2.0"
			(at 381 156.21 0)
			(effects
				(font
					(size 1.27 1.27)
					(thickness 0.15)
				)
				(justify left bottom)
				(hide yes)
			)
		)
		(pin "1"
		)
		(instances
			(project "jetson-agx-thor-baseboard"
				(path ""
					(reference "TP97")
					(unit 1)
				)
			)
		)
	)
	(symbol
		(lib_id "antmicropower:+3V3")
		(at 294.64 146.05 90)
		(unit 1)
		(exclude_from_sim no)
		(in_bom yes)
		(on_board yes)
		(dnp no)
		(property "Reference" "#PWR0643"
			(at 298.45 146.05 0)
			(effects
				(font
					(size 1.27 1.27)
				)
				(justify left bottom)
				(hide yes)
			)
		)
		(property "Value" "+3V3"
			(at 291.338 146.05 90)
			(effects
				(font
					(size 1.27 1.27)
					(thickness 0.15)
				)
				(justify left)
			)
		)
		(property "Footprint" ""
			(at 302.26 130.81 0)
			(effects
				(font
					(size 1.27 1.27)
					(thickness 0.15)
				)
				(justify left bottom)
				(hide yes)
			)
		)
		(property "Datasheet" ""
			(at 304.8 130.81 0)
			(effects
				(font
					(size 1.27 1.27)
					(thickness 0.15)
				)
				(justify left bottom)
				(hide yes)
			)
		)
		(property "Description" ""
			(at 294.64 146.05 0)
			(effects
				(font
					(size 1.27 1.27)
				)
				(hide yes)
			)
		)
		(property "Author" "Antmicro"
			(at 297.18 130.81 0)
			(effects
				(font
					(size 1.27 1.27)
					(thickness 0.15)
				)
				(justify left bottom)
				(hide yes)
			)
		)
		(property "License" "Apache-2.0"
			(at 299.72 130.81 0)
			(effects
				(font
					(size 1.27 1.27)
					(thickness 0.15)
				)
				(justify left bottom)
				(hide yes)
			)
		)
		(pin "1"
		)
		(instances
			(project "jetson-agx-thor-baseboard"
				(path ""
					(reference "#PWR0643")
					(unit 1)
				)
			)
		)
	)
	(symbol
		(lib_id "antmicropower:GND")
		(at 116.84 151.13 0)
		(unit 1)
		(exclude_from_sim no)
		(in_bom yes)
		(on_board yes)
		(dnp no)
		(fields_autoplaced yes)
		(property "Reference" "#PWR0396"
			(at 116.84 157.48 0)
			(effects
				(font
					(size 1.27 1.27)
				)
				(justify left bottom)
				(hide yes)
			)
		)
		(property "Value" "GND"
			(at 116.84 154.94 0)
			(effects
				(font
					(size 1.27 1.27)
					(thickness 0.15)
				)
			)
		)
		(property "Footprint" ""
			(at 125.73 158.75 0)
			(effects
				(font
					(size 1.27 1.27)
					(thickness 0.15)
				)
				(justify left bottom)
				(hide yes)
			)
		)
		(property "Datasheet" ""
			(at 125.73 163.83 0)
			(effects
				(font
					(size 1.27 1.27)
					(thickness 0.15)
				)
				(justify left bottom)
				(hide yes)
			)
		)
		(property "Description" ""
			(at 116.84 151.13 0)
			(effects
				(font
					(size 1.27 1.27)
				)
				(hide yes)
			)
		)
		(property "Author" "Antmicro"
			(at 125.73 158.75 0)
			(effects
				(font
					(size 1.27 1.27)
					(thickness 0.15)
				)
				(justify left bottom)
				(hide yes)
			)
		)
		(property "License" "Apache-2.0"
			(at 125.73 161.29 0)
			(effects
				(font
					(size 1.27 1.27)
					(thickness 0.15)
				)
				(justify left bottom)
				(hide yes)
			)
		)
		(pin "1"
		)
		(instances
			(project "jetson-agx-thor-baseboard"
				(path ""
					(reference "#PWR0396")
					(unit 1)
				)
			)
		)
	)
	(symbol
		(lib_id "antmicroTVSDiodes:TPD4E05U06QDQARQ1")
		(at 318.77 88.9 270)
		(unit 1)
		(exclude_from_sim no)
		(in_bom yes)
		(on_board yes)
		(dnp no)
		(property "Reference" "U68"
			(at 306.832 99.06 90)
			(effects
				(font
					(size 1.27 1.27)
				)
				(justify left)
			)
		)
		(property "Value" "TPD4E05U06QDQARQ1"
			(at 308.61 113.03 0)
			(effects
				(font
					(size 1.27 1.27)
					(thickness 0.15)
				)
				(justify left bottom)
				(hide yes)
			)
		)
		(property "Footprint" "antmicro-footprints:USON-10_2.5x1mm_P0.5mm"
			(at 313.69 113.03 0)
			(effects
				(font
					(size 1.27 1.27)
					(thickness 0.15)
				)
				(justify left bottom)
				(hide yes)
			)
		)
		(property "Datasheet" "https://www.ti.com/lit/ds/symlink/tpd4e05u06-q1.pdf?HQS=dis-mous-null-mousermode-dsf-pf-null-wwe&ts=1663591265741&ref_url=https%253A%252F%252Fwww.mouser.com%252F"
			(at 311.15 113.03 0)
			(effects
				(font
					(size 1.27 1.27)
					(thickness 0.15)
				)
				(justify left bottom)
				(hide yes)
			)
		)
		(property "Description" "TVS diode array, 12 kV, USON-10, 5.5 V, 0.5 pF"
			(at 318.77 88.9 0)
			(effects
				(font
					(size 1.27 1.27)
				)
				(hide yes)
			)
		)
		(property "Manufacturer" "Texas Instruments"
			(at 306.07 113.03 0)
			(effects
				(font
					(size 1.27 1.27)
					(thickness 0.15)
				)
				(justify left bottom)
				(hide yes)
			)
		)
		(property "MPN" "TPD4E05U06QDQARQ1"
			(at 306.832 101.346 90)
			(effects
				(font
					(size 1.27 1.27)
					(thickness 0.15)
				)
				(justify left)
			)
		)
		(property "Author" "Antmicro"
			(at 303.53 113.03 0)
			(effects
				(font
					(size 1.27 1.27)
					(thickness 0.15)
				)
				(justify left bottom)
				(hide yes)
			)
		)
		(property "License" "Apache-2.0"
			(at 300.99 113.03 0)
			(effects
				(font
					(size 1.27 1.27)
					(thickness 0.15)
				)
				(justify left bottom)
				(hide yes)
			)
		)
		(pin "1"
		)
		(pin "10"
		)
		(pin "2"
		)
		(pin "3"
		)
		(pin "4"
		)
		(pin "5"
		)
		(pin "6"
		)
		(pin "7"
		)
		(pin "8"
		)
		(pin "9"
		)
		(instances
			(project "jetson-agx-thor-baseboard"
				(path ""
					(reference "U68")
					(unit 1)
				)
			)
		)
	)
	(symbol
		(lib_id "antmicroCapacitors0402:C_100n_0402")
		(at 67.31 36.83 90)
		(unit 1)
		(exclude_from_sim no)
		(in_bom yes)
		(on_board yes)
		(dnp no)
		(property "Reference" "C205"
			(at 69.088 32.766 90)
			(effects
				(font
					(size 1.27 1.27)
					(thickness 0.15)
				)
				(justify right)
			)
		)
		(property "Value" "C_100n_0402"
			(at 90.17 21.59 0)
			(effects
				(font
					(size 1.27 1.27)
					(thickness 0.15)
				)
				(justify left bottom)
				(hide yes)
			)
		)
		(property "Footprint" "antmicro-footprints:C_0402_1005Metric"
			(at 92.71 21.59 0)
			(effects
				(font
					(size 1.27 1.27)
					(thickness 0.15)
				)
				(justify left bottom)
				(hide yes)
			)
		)
		(property "Datasheet" "https://www.murata.com/products/productdetail?partno=GRM155R61H104KE14%23"
			(at 95.25 21.59 0)
			(effects
				(font
					(size 1.27 1.27)
					(thickness 0.15)
				)
				(justify left bottom)
				(hide yes)
			)
		)
		(property "Description" "SMD Multilayer Ceramic Capacitor, 0.1 µF, 50 V, 0402 [1005 Metric], ± 10%, X5R, GRM Series"
			(at 67.31 36.83 0)
			(effects
				(font
					(size 1.27 1.27)
				)
				(hide yes)
			)
		)
		(property "MPN" "GRM155R61H104KE14D"
			(at 97.79 21.59 0)
			(effects
				(font
					(size 1.27 1.27)
					(thickness 0.15)
				)
				(justify left bottom)
				(hide yes)
			)
		)
		(property "Val" "100n"
			(at 69.088 35.306 90)
			(effects
				(font
					(size 1.27 1.27)
					(thickness 0.15)
				)
				(justify right)
			)
		)
		(property "Voltage" "50V"
			(at 77.47 21.59 0)
			(effects
				(font
					(size 1.27 1.27)
					(thickness 0.15)
				)
				(justify left bottom)
				(hide yes)
			)
		)
		(property "Dielectric" "X5R"
			(at 80.01 21.59 0)
			(effects
				(font
					(size 1.27 1.27)
					(thickness 0.15)
				)
				(justify left bottom)
				(hide yes)
			)
		)
		(property "Manufacturer" "Murata"
			(at 82.55 21.59 0)
			(effects
				(font
					(size 1.27 1.27)
					(thickness 0.15)
				)
				(justify left bottom)
				(hide yes)
			)
		)
		(property "License" "Apache-2.0"
			(at 85.09 21.59 0)
			(effects
				(font
					(size 1.27 1.27)
					(thickness 0.15)
				)
				(justify left bottom)
				(hide yes)
			)
		)
		(property "Author" "Antmicro"
			(at 87.63 21.59 0)
			(effects
				(font
					(size 1.27 1.27)
					(thickness 0.15)
				)
				(justify left bottom)
				(hide yes)
			)
		)
		(pin "1"
		)
		(pin "2"
		)
		(instances
			(project "jetson-agx-thor-baseboard"
				(path ""
					(reference "C205")
					(unit 1)
				)
			)
		)
	)
	(symbol
		(lib_id "antmicroResistors0402:R_200R_0402")
		(at 53.34 208.28 90)
		(unit 1)
		(exclude_from_sim no)
		(in_bom yes)
		(on_board yes)
		(dnp no)
		(property "Reference" "R231"
			(at 54.61 204.47 90)
			(effects
				(font
					(size 1.27 1.27)
				)
				(justify right)
			)
		)
		(property "Value" "R_200R_0402"
			(at 66.04 187.96 0)
			(effects
				(font
					(size 1.27 1.27)
					(thickness 0.15)
				)
				(justify left bottom)
				(hide yes)
			)
		)
		(property "Footprint" "antmicro-footprints:R_0402_1005Metric"
			(at 68.58 187.96 0)
			(effects
				(font
					(size 1.27 1.27)
					(thickness 0.15)
				)
				(justify left bottom)
				(hide yes)
			)
		)
		(property "Datasheet" "https://www.bourns.com/docs/product-datasheets/cr.pdf"
			(at 71.12 187.96 0)
			(effects
				(font
					(size 1.27 1.27)
					(thickness 0.15)
				)
				(justify left bottom)
				(hide yes)
			)
		)
		(property "Description" "SMD Chip Resistor, 200 ohm, ± 1%, 62.5 mW, 0402 [1005 Metric], Thick Film, General Purpose"
			(at 53.34 208.28 0)
			(effects
				(font
					(size 1.27 1.27)
				)
				(hide yes)
			)
		)
		(property "Manufacturer" "Bourns"
			(at 76.2 187.96 0)
			(effects
				(font
					(size 1.27 1.27)
					(thickness 0.15)
				)
				(justify left bottom)
				(hide yes)
			)
		)
		(property "MPN" "CR0402-FX-2000GLF"
			(at 73.66 187.96 0)
			(effects
				(font
					(size 1.27 1.27)
					(thickness 0.15)
				)
				(justify left bottom)
				(hide yes)
			)
		)
		(property "Val" "200R"
			(at 54.61 207.01 90)
			(effects
				(font
					(size 1.27 1.27)
					(thickness 0.15)
				)
				(justify right)
			)
		)
		(property "License" "Apache-2.0"
			(at 78.74 187.96 0)
			(effects
				(font
					(size 1.27 1.27)
					(thickness 0.15)
				)
				(justify left bottom)
				(hide yes)
			)
		)
		(property "Author" "Antmicro"
			(at 81.28 187.96 0)
			(effects
				(font
					(size 1.27 1.27)
					(thickness 0.15)
				)
				(justify left bottom)
				(hide yes)
			)
		)
		(property "Tolerance" "1%"
			(at 63.5 187.96 0)
			(effects
				(font
					(size 1.27 1.27)
				)
				(justify left bottom)
				(hide yes)
			)
		)
		(pin "1"
		)
		(pin "2"
		)
		(instances
			(project "jetson-agx-thor-baseboard"
				(path ""
					(reference "R231")
					(unit 1)
				)
			)
		)
	)
	(symbol
		(lib_id "antmicropower:+3V3")
		(at 290.83 121.92 0)
		(unit 1)
		(exclude_from_sim no)
		(in_bom yes)
		(on_board yes)
		(dnp no)
		(property "Reference" "#PWR0645"
			(at 290.83 125.73 0)
			(effects
				(font
					(size 1.27 1.27)
				)
				(justify left bottom)
				(hide yes)
			)
		)
		(property "Value" "+3V3"
			(at 287.655 118.11 0)
			(effects
				(font
					(size 1.27 1.27)
					(thickness 0.15)
				)
				(justify left)
			)
		)
		(property "Footprint" ""
			(at 306.07 129.54 0)
			(effects
				(font
					(size 1.27 1.27)
					(thickness 0.15)
				)
				(justify left bottom)
				(hide yes)
			)
		)
		(property "Datasheet" ""
			(at 306.07 132.08 0)
			(effects
				(font
					(size 1.27 1.27)
					(thickness 0.15)
				)
				(justify left bottom)
				(hide yes)
			)
		)
		(property "Description" ""
			(at 290.83 121.92 0)
			(effects
				(font
					(size 1.27 1.27)
				)
				(hide yes)
			)
		)
		(property "Author" "Antmicro"
			(at 306.07 124.46 0)
			(effects
				(font
					(size 1.27 1.27)
					(thickness 0.15)
				)
				(justify left bottom)
				(hide yes)
			)
		)
		(property "License" "Apache-2.0"
			(at 306.07 127 0)
			(effects
				(font
					(size 1.27 1.27)
					(thickness 0.15)
				)
				(justify left bottom)
				(hide yes)
			)
		)
		(pin "1"
		)
		(instances
			(project "jetson-agx-thor-baseboard"
				(path ""
					(reference "#PWR0645")
					(unit 1)
				)
			)
		)
	)
	(symbol
		(lib_id "antmicroResistors0402:R_10k_0402")
		(at 57.15 64.77 270)
		(mirror x)
		(unit 1)
		(exclude_from_sim no)
		(in_bom yes)
		(on_board yes)
		(dnp no)
		(property "Reference" "R232"
			(at 56.134 60.96 90)
			(effects
				(font
					(size 1.27 1.27)
					(thickness 0.15)
				)
				(justify right)
			)
		)
		(property "Value" "R_10k_0402"
			(at 44.45 44.45 0)
			(effects
				(font
					(size 1.27 1.27)
					(thickness 0.15)
				)
				(justify left bottom)
				(hide yes)
			)
		)
		(property "Footprint" "antmicro-footprints:R_0402_1005Metric"
			(at 41.91 44.45 0)
			(effects
				(font
					(size 1.27 1.27)
					(thickness 0.15)
				)
				(justify left bottom)
				(hide yes)
			)
		)
		(property "Datasheet" "https://www.bourns.com/docs/product-datasheets/cr.pdf"
			(at 39.37 44.45 0)
			(effects
				(font
					(size 1.27 1.27)
					(thickness 0.15)
				)
				(justify left bottom)
				(hide yes)
			)
		)
		(property "Description" "SMD Chip Resistor, 10 kohm, ± 1%, 62.5 mW, 0402 [1005 Metric], Thick Film, General Purpose"
			(at 57.15 64.77 0)
			(effects
				(font
					(size 1.27 1.27)
				)
				(hide yes)
			)
		)
		(property "MPN" "CR0402-FX-1002GLF"
			(at 36.83 44.45 0)
			(effects
				(font
					(size 1.27 1.27)
					(thickness 0.15)
				)
				(justify left bottom)
				(hide yes)
			)
		)
		(property "Manufacturer" "Bourns"
			(at 34.29 44.45 0)
			(effects
				(font
					(size 1.27 1.27)
					(thickness 0.15)
				)
				(justify left bottom)
				(hide yes)
			)
		)
		(property "License" "Apache-2.0"
			(at 31.75 44.45 0)
			(effects
				(font
					(size 1.27 1.27)
					(thickness 0.15)
				)
				(justify left bottom)
				(hide yes)
			)
		)
		(property "Author" "Antmicro"
			(at 29.21 44.45 0)
			(effects
				(font
					(size 1.27 1.27)
					(thickness 0.15)
				)
				(justify left bottom)
				(hide yes)
			)
		)
		(property "Val" "10k"
			(at 56.134 63.5 90)
			(effects
				(font
					(size 1.27 1.27)
					(thickness 0.15)
				)
				(justify right)
			)
		)
		(property "Tolerance" "1%"
			(at 46.99 44.45 0)
			(effects
				(font
					(size 1.27 1.27)
				)
				(justify left bottom)
				(hide yes)
			)
		)
		(pin "2"
		)
		(pin "1"
		)
		(instances
			(project "jetson-agx-thor-baseboard"
				(path ""
					(reference "R232")
					(unit 1)
				)
			)
		)
	)
	(symbol
		(lib_id "antmicroResistors0402:R_0R_0402")
		(at 342.9 144.78 0)
		(unit 1)
		(exclude_from_sim no)
		(in_bom yes)
		(on_board yes)
		(dnp no)
		(property "Reference" "R405"
			(at 340.868 143.764 0)
			(effects
				(font
					(size 1.27 1.27)
					(thickness 0.15)
				)
			)
		)
		(property "Value" "R_0R_0402"
			(at 363.22 157.48 0)
			(effects
				(font
					(size 1.27 1.27)
					(thickness 0.15)
				)
				(justify left bottom)
				(hide yes)
			)
		)
		(property "Footprint" "antmicro-footprints:R_0402_1005Metric"
			(at 363.22 160.02 0)
			(effects
				(font
					(size 1.27 1.27)
					(thickness 0.15)
				)
				(justify left bottom)
				(hide yes)
			)
		)
		(property "Datasheet" "https://industrial.panasonic.com/cdbs/www-data/pdf/RDA0000/AOA0000C301.pdf"
			(at 363.22 162.56 0)
			(effects
				(font
					(size 1.27 1.27)
					(thickness 0.15)
				)
				(justify left bottom)
				(hide yes)
			)
		)
		(property "Description" "SMD Chip Resistor, Jumper, 0 ohm, 100 mW, 0402 [1005 Metric], Thick Film, General Purpose"
			(at 363.22 177.8 0)
			(effects
				(font
					(size 1.27 1.27)
				)
				(justify left bottom)
				(hide yes)
			)
		)
		(property "MPN" "ERJ2GE0R00X"
			(at 363.22 165.1 0)
			(effects
				(font
					(size 1.27 1.27)
					(thickness 0.15)
				)
				(justify left bottom)
				(hide yes)
			)
		)
		(property "Manufacturer" "Panasonic"
			(at 363.22 167.64 0)
			(effects
				(font
					(size 1.27 1.27)
					(thickness 0.15)
				)
				(justify left bottom)
				(hide yes)
			)
		)
		(property "License" "Apache-2.0"
			(at 363.22 170.18 0)
			(effects
				(font
					(size 1.27 1.27)
					(thickness 0.15)
				)
				(justify left bottom)
				(hide yes)
			)
		)
		(property "Author" "Antmicro"
			(at 363.22 172.72 0)
			(effects
				(font
					(size 1.27 1.27)
					(thickness 0.15)
				)
				(justify left bottom)
				(hide yes)
			)
		)
		(property "Val" "0R"
			(at 348.742 143.764 0)
			(effects
				(font
					(size 1.27 1.27)
					(thickness 0.15)
				)
			)
		)
		(property "Tolerance" "~"
			(at 363.22 154.94 0)
			(effects
				(font
					(size 1.27 1.27)
				)
				(justify left bottom)
				(hide yes)
			)
		)
		(property "Current" "1A"
			(at 363.22 175.26 0)
			(effects
				(font
					(size 1.27 1.27)
					(thickness 0.15)
				)
				(justify left bottom)
				(hide yes)
			)
		)
		(pin "2"
		)
		(pin "1"
		)
		(instances
			(project "jetson-agx-thor-baseboard"
				(path ""
					(reference "R405")
					(unit 1)
				)
			)
		)
	)
	(symbol
		(lib_id "antmicropower:GND")
		(at 102.87 231.14 0)
		(unit 1)
		(exclude_from_sim no)
		(in_bom yes)
		(on_board yes)
		(dnp no)
		(fields_autoplaced yes)
		(property "Reference" "#PWR0400"
			(at 102.87 237.49 0)
			(effects
				(font
					(size 1.27 1.27)
				)
				(justify left bottom)
				(hide yes)
			)
		)
		(property "Value" "GND"
			(at 102.87 234.95 0)
			(effects
				(font
					(size 1.27 1.27)
					(thickness 0.15)
				)
			)
		)
		(property "Footprint" ""
			(at 111.76 238.76 0)
			(effects
				(font
					(size 1.27 1.27)
					(thickness 0.15)
				)
				(justify left bottom)
				(hide yes)
			)
		)
		(property "Datasheet" ""
			(at 111.76 243.84 0)
			(effects
				(font
					(size 1.27 1.27)
					(thickness 0.15)
				)
				(justify left bottom)
				(hide yes)
			)
		)
		(property "Description" ""
			(at 102.87 231.14 0)
			(effects
				(font
					(size 1.27 1.27)
				)
				(hide yes)
			)
		)
		(property "Author" "Antmicro"
			(at 111.76 238.76 0)
			(effects
				(font
					(size 1.27 1.27)
					(thickness 0.15)
				)
				(justify left bottom)
				(hide yes)
			)
		)
		(property "License" "Apache-2.0"
			(at 111.76 241.3 0)
			(effects
				(font
					(size 1.27 1.27)
					(thickness 0.15)
				)
				(justify left bottom)
				(hide yes)
			)
		)
		(pin "1"
		)
		(instances
			(project "jetson-agx-thor-baseboard"
				(path ""
					(reference "#PWR0400")
					(unit 1)
				)
			)
		)
	)
	(symbol
		(lib_id "antmicroResistors0402:R_0R_0402")
		(at 342.9 132.08 0)
		(unit 1)
		(exclude_from_sim no)
		(in_bom yes)
		(on_board yes)
		(dnp no)
		(property "Reference" "R346"
			(at 340.868 131.064 0)
			(effects
				(font
					(size 1.27 1.27)
					(thickness 0.15)
				)
			)
		)
		(property "Value" "R_0R_0402"
			(at 363.22 144.78 0)
			(effects
				(font
					(size 1.27 1.27)
					(thickness 0.15)
				)
				(justify left bottom)
				(hide yes)
			)
		)
		(property "Footprint" "antmicro-footprints:R_0402_1005Metric"
			(at 363.22 147.32 0)
			(effects
				(font
					(size 1.27 1.27)
					(thickness 0.15)
				)
				(justify left bottom)
				(hide yes)
			)
		)
		(property "Datasheet" "https://industrial.panasonic.com/cdbs/www-data/pdf/RDA0000/AOA0000C301.pdf"
			(at 363.22 149.86 0)
			(effects
				(font
					(size 1.27 1.27)
					(thickness 0.15)
				)
				(justify left bottom)
				(hide yes)
			)
		)
		(property "Description" "SMD Chip Resistor, Jumper, 0 ohm, 100 mW, 0402 [1005 Metric], Thick Film, General Purpose"
			(at 363.22 165.1 0)
			(effects
				(font
					(size 1.27 1.27)
				)
				(justify left bottom)
				(hide yes)
			)
		)
		(property "MPN" "ERJ2GE0R00X"
			(at 363.22 152.4 0)
			(effects
				(font
					(size 1.27 1.27)
					(thickness 0.15)
				)
				(justify left bottom)
				(hide yes)
			)
		)
		(property "Manufacturer" "Panasonic"
			(at 363.22 154.94 0)
			(effects
				(font
					(size 1.27 1.27)
					(thickness 0.15)
				)
				(justify left bottom)
				(hide yes)
			)
		)
		(property "License" "Apache-2.0"
			(at 363.22 157.48 0)
			(effects
				(font
					(size 1.27 1.27)
					(thickness 0.15)
				)
				(justify left bottom)
				(hide yes)
			)
		)
		(property "Author" "Antmicro"
			(at 363.22 160.02 0)
			(effects
				(font
					(size 1.27 1.27)
					(thickness 0.15)
				)
				(justify left bottom)
				(hide yes)
			)
		)
		(property "Val" "0R"
			(at 348.742 131.064 0)
			(effects
				(font
					(size 1.27 1.27)
					(thickness 0.15)
				)
			)
		)
		(property "Tolerance" "~"
			(at 363.22 142.24 0)
			(effects
				(font
					(size 1.27 1.27)
				)
				(justify left bottom)
				(hide yes)
			)
		)
		(property "Current" "1A"
			(at 363.22 162.56 0)
			(effects
				(font
					(size 1.27 1.27)
					(thickness 0.15)
				)
				(justify left bottom)
				(hide yes)
			)
		)
		(pin "2"
		)
		(pin "1"
		)
		(instances
			(project "jetson-agx-thor-baseboard"
				(path ""
					(reference "R346")
					(unit 1)
				)
			)
		)
	)
	(symbol
		(lib_id "antmicropower:GND")
		(at 218.44 154.94 0)
		(mirror y)
		(unit 1)
		(exclude_from_sim no)
		(in_bom yes)
		(on_board yes)
		(dnp no)
		(property "Reference" "#PWR0629"
			(at 209.55 157.48 0)
			(effects
				(font
					(size 1.27 1.27)
					(thickness 0.15)
				)
				(justify left bottom)
				(hide yes)
			)
		)
		(property "Value" "GND"
			(at 218.44 159.004 0)
			(effects
				(font
					(size 1.27 1.27)
					(thickness 0.15)
				)
			)
		)
		(property "Footprint" ""
			(at 209.55 162.56 0)
			(effects
				(font
					(size 1.27 1.27)
					(thickness 0.15)
				)
				(justify left bottom)
				(hide yes)
			)
		)
		(property "Datasheet" ""
			(at 209.55 167.64 0)
			(effects
				(font
					(size 1.27 1.27)
					(thickness 0.15)
				)
				(justify left bottom)
				(hide yes)
			)
		)
		(property "Description" ""
			(at 209.55 170.18 0)
			(effects
				(font
					(size 1.27 1.27)
				)
				(justify left bottom)
				(hide yes)
			)
		)
		(property "Author" "Antmicro"
			(at 209.55 162.56 0)
			(effects
				(font
					(size 1.27 1.27)
					(thickness 0.15)
				)
				(justify left bottom)
				(hide yes)
			)
		)
		(property "License" "Apache-2.0"
			(at 209.55 165.1 0)
			(effects
				(font
					(size 1.27 1.27)
					(thickness 0.15)
				)
				(justify left bottom)
				(hide yes)
			)
		)
		(pin "1"
		)
		(instances
			(project "jetson-agx-thor-baseboard"
				(path ""
					(reference "#PWR0629")
					(unit 1)
				)
			)
		)
	)
	(symbol
		(lib_id "antmicropower:+3V3")
		(at 264.16 36.83 0)
		(unit 1)
		(exclude_from_sim no)
		(in_bom yes)
		(on_board yes)
		(dnp no)
		(property "Reference" "#PWR0418"
			(at 264.16 40.64 0)
			(effects
				(font
					(size 1.27 1.27)
				)
				(justify left bottom)
				(hide yes)
			)
		)
		(property "Value" "+3V3"
			(at 260.985 33.02 0)
			(effects
				(font
					(size 1.27 1.27)
					(thickness 0.15)
				)
				(justify left)
			)
		)
		(property "Footprint" ""
			(at 279.4 44.45 0)
			(effects
				(font
					(size 1.27 1.27)
					(thickness 0.15)
				)
				(justify left bottom)
				(hide yes)
			)
		)
		(property "Datasheet" ""
			(at 279.4 46.99 0)
			(effects
				(font
					(size 1.27 1.27)
					(thickness 0.15)
				)
				(justify left bottom)
				(hide yes)
			)
		)
		(property "Description" ""
			(at 264.16 36.83 0)
			(effects
				(font
					(size 1.27 1.27)
				)
				(hide yes)
			)
		)
		(property "Author" "Antmicro"
			(at 279.4 39.37 0)
			(effects
				(font
					(size 1.27 1.27)
					(thickness 0.15)
				)
				(justify left bottom)
				(hide yes)
			)
		)
		(property "License" "Apache-2.0"
			(at 279.4 41.91 0)
			(effects
				(font
					(size 1.27 1.27)
					(thickness 0.15)
				)
				(justify left bottom)
				(hide yes)
			)
		)
		(pin "1"
		)
		(instances
			(project "jetson-agx-thor-baseboard"
				(path ""
					(reference "#PWR0418")
					(unit 1)
				)
			)
		)
	)
	(symbol
		(lib_id "antmicroResistors0402:R_10k_0402")
		(at 78.74 76.2 90)
		(unit 1)
		(exclude_from_sim no)
		(in_bom yes)
		(on_board yes)
		(dnp no)
		(property "Reference" "R230"
			(at 79.756 72.39 90)
			(effects
				(font
					(size 1.27 1.27)
					(thickness 0.15)
				)
				(justify right)
			)
		)
		(property "Value" "R_10k_0402"
			(at 91.44 55.88 0)
			(effects
				(font
					(size 1.27 1.27)
					(thickness 0.15)
				)
				(justify left bottom)
				(hide yes)
			)
		)
		(property "Footprint" "antmicro-footprints:R_0402_1005Metric"
			(at 93.98 55.88 0)
			(effects
				(font
					(size 1.27 1.27)
					(thickness 0.15)
				)
				(justify left bottom)
				(hide yes)
			)
		)
		(property "Datasheet" "https://www.bourns.com/docs/product-datasheets/cr.pdf"
			(at 96.52 55.88 0)
			(effects
				(font
					(size 1.27 1.27)
					(thickness 0.15)
				)
				(justify left bottom)
				(hide yes)
			)
		)
		(property "Description" "SMD Chip Resistor, 10 kohm, ± 1%, 62.5 mW, 0402 [1005 Metric], Thick Film, General Purpose"
			(at 78.74 76.2 0)
			(effects
				(font
					(size 1.27 1.27)
				)
				(hide yes)
			)
		)
		(property "MPN" "CR0402-FX-1002GLF"
			(at 99.06 55.88 0)
			(effects
				(font
					(size 1.27 1.27)
					(thickness 0.15)
				)
				(justify left bottom)
				(hide yes)
			)
		)
		(property "Manufacturer" "Bourns"
			(at 101.6 55.88 0)
			(effects
				(font
					(size 1.27 1.27)
					(thickness 0.15)
				)
				(justify left bottom)
				(hide yes)
			)
		)
		(property "License" "Apache-2.0"
			(at 104.14 55.88 0)
			(effects
				(font
					(size 1.27 1.27)
					(thickness 0.15)
				)
				(justify left bottom)
				(hide yes)
			)
		)
		(property "Author" "Antmicro"
			(at 106.68 55.88 0)
			(effects
				(font
					(size 1.27 1.27)
					(thickness 0.15)
				)
				(justify left bottom)
				(hide yes)
			)
		)
		(property "Val" "10k"
			(at 79.756 74.93 90)
			(effects
				(font
					(size 1.27 1.27)
					(thickness 0.15)
				)
				(justify right)
			)
		)
		(property "Tolerance" "1%"
			(at 88.9 55.88 0)
			(effects
				(font
					(size 1.27 1.27)
				)
				(justify left bottom)
				(hide yes)
			)
		)
		(pin "2"
		)
		(pin "1"
		)
		(instances
			(project "jetson-agx-thor-baseboard"
				(path ""
					(reference "R230")
					(unit 1)
				)
			)
		)
	)
	(symbol
		(lib_id "antmicroTVSDiodes:TPD1E0B04_XDFN-2")
		(at 204.47 217.17 90)
		(unit 1)
		(exclude_from_sim no)
		(in_bom yes)
		(on_board yes)
		(dnp no)
		(property "Reference" "D37"
			(at 202.565 213.36 90)
			(effects
				(font
					(size 1.27 1.27)
				)
				(justify left)
			)
		)
		(property "Value" "TPD1E0B04_XDFN-2"
			(at 214.63 201.93 0)
			(effects
				(font
					(size 1.27 1.27)
					(thickness 0.15)
				)
				(justify left bottom)
				(hide yes)
			)
		)
		(property "Footprint" "antmicro-footprints:XDFN-2_1x0.60mm"
			(at 209.55 201.93 0)
			(effects
				(font
					(size 1.27 1.27)
					(thickness 0.15)
				)
				(justify left bottom)
				(hide yes)
			)
		)
		(property "Datasheet" "https://www.ti.com/general/docs/suppproductinfo.tsp?distId=26&gotoUrl=https://www.ti.com/lit/gpn/tpd1e0b04"
			(at 212.09 201.93 0)
			(effects
				(font
					(size 1.27 1.27)
					(thickness 0.15)
				)
				(justify left bottom)
				(hide yes)
			)
		)
		(property "Description" "Bidirectional TVS, 8 kV,  XDFN-2, 3.6 V, 0.18 pF"
			(at 204.47 217.17 0)
			(effects
				(font
					(size 1.27 1.27)
				)
				(hide yes)
			)
		)
		(property "Manufacturer" "Texas Instruments"
			(at 217.17 201.93 0)
			(effects
				(font
					(size 1.27 1.27)
					(thickness 0.15)
				)
				(justify left bottom)
				(hide yes)
			)
		)
		(property "MPN" "TPD1E0B04DPYR"
			(at 202.565 215.9 90)
			(effects
				(font
					(size 1.27 1.27)
					(thickness 0.15)
				)
				(justify left)
			)
		)
		(property "Author" "Antmicro"
			(at 219.71 201.93 0)
			(effects
				(font
					(size 1.27 1.27)
					(thickness 0.15)
				)
				(justify left bottom)
				(hide yes)
			)
		)
		(property "License" "Apache-2.0"
			(at 222.25 201.93 0)
			(effects
				(font
					(size 1.27 1.27)
					(thickness 0.15)
				)
				(justify left bottom)
				(hide yes)
			)
		)
		(pin "1"
		)
		(pin "2"
		)
		(instances
			(project "jetson-agx-thor-baseboard"
				(path ""
					(reference "D37")
					(unit 1)
				)
			)
		)
	)
	(symbol
		(lib_id "antmicroCapacitors0402:C_100n_0402")
		(at 73.66 132.08 270)
		(mirror x)
		(unit 1)
		(exclude_from_sim no)
		(in_bom yes)
		(on_board yes)
		(dnp no)
		(property "Reference" "C206"
			(at 75.565 128.27 90)
			(effects
				(font
					(size 1.27 1.27)
				)
				(justify left)
			)
		)
		(property "Value" "C_100n_0402"
			(at 63.5 111.76 0)
			(effects
				(font
					(size 1.27 1.27)
					(thickness 0.15)
				)
				(justify left bottom)
				(hide yes)
			)
		)
		(property "Footprint" "antmicro-footprints:C_0402_1005Metric"
			(at 60.96 111.76 0)
			(effects
				(font
					(size 1.27 1.27)
					(thickness 0.15)
				)
				(justify left bottom)
				(hide yes)
			)
		)
		(property "Datasheet" "https://www.murata.com/products/productdetail?partno=GRM155R61H104KE14%23"
			(at 58.42 111.76 0)
			(effects
				(font
					(size 1.27 1.27)
					(thickness 0.15)
				)
				(justify left bottom)
				(hide yes)
			)
		)
		(property "Description" "SMD Multilayer Ceramic Capacitor, 0.1 µF, 50 V, 0402 [1005 Metric], ± 10%, X5R, GRM Series"
			(at 73.66 132.08 0)
			(effects
				(font
					(size 1.27 1.27)
				)
				(hide yes)
			)
		)
		(property "Manufacturer" "Murata"
			(at 53.34 111.76 0)
			(effects
				(font
					(size 1.27 1.27)
					(thickness 0.15)
				)
				(justify left bottom)
				(hide yes)
			)
		)
		(property "MPN" "GRM155R61H104KE14D"
			(at 55.88 111.76 0)
			(effects
				(font
					(size 1.27 1.27)
					(thickness 0.15)
				)
				(justify left bottom)
				(hide yes)
			)
		)
		(property "Val" "100n"
			(at 75.565 130.81 90)
			(effects
				(font
					(size 1.27 1.27)
					(thickness 0.15)
				)
				(justify left)
			)
		)
		(property "License" "Apache-2.0"
			(at 50.8 111.76 0)
			(effects
				(font
					(size 1.27 1.27)
					(thickness 0.15)
				)
				(justify left bottom)
				(hide yes)
			)
		)
		(property "Author" "Antmicro"
			(at 48.26 111.76 0)
			(effects
				(font
					(size 1.27 1.27)
					(thickness 0.15)
				)
				(justify left bottom)
				(hide yes)
			)
		)
		(property "Voltage" "50V"
			(at 45.72 111.76 0)
			(effects
				(font
					(size 1.27 1.27)
				)
				(justify left bottom)
				(hide yes)
			)
		)
		(property "Dielectric" "X5R"
			(at 43.18 111.76 0)
			(effects
				(font
					(size 1.27 1.27)
				)
				(justify left bottom)
				(hide yes)
			)
		)
		(pin "1"
		)
		(pin "2"
		)
		(instances
			(project "jetson-agx-thor-baseboard"
				(path ""
					(reference "C206")
					(unit 1)
				)
			)
		)
	)
	(symbol
		(lib_id "antmicroCapacitors0402:C_100n_0402")
		(at 290.83 129.54 90)
		(unit 1)
		(exclude_from_sim no)
		(in_bom yes)
		(on_board yes)
		(dnp no)
		(property "Reference" "C313"
			(at 292.735 125.73 90)
			(effects
				(font
					(size 1.27 1.27)
				)
				(justify right)
			)
		)
		(property "Value" "C_100n_0402"
			(at 300.99 109.22 0)
			(effects
				(font
					(size 1.27 1.27)
					(thickness 0.15)
				)
				(justify left bottom)
				(hide yes)
			)
		)
		(property "Footprint" "antmicro-footprints:C_0402_1005Metric"
			(at 303.53 109.22 0)
			(effects
				(font
					(size 1.27 1.27)
					(thickness 0.15)
				)
				(justify left bottom)
				(hide yes)
			)
		)
		(property "Datasheet" "https://www.murata.com/products/productdetail?partno=GRM155R61H104KE14%23"
			(at 306.07 109.22 0)
			(effects
				(font
					(size 1.27 1.27)
					(thickness 0.15)
				)
				(justify left bottom)
				(hide yes)
			)
		)
		(property "Description" "SMD Multilayer Ceramic Capacitor, 0.1 µF, 50 V, 0402 [1005 Metric], ± 10%, X5R, GRM Series"
			(at 290.83 129.54 0)
			(effects
				(font
					(size 1.27 1.27)
				)
				(hide yes)
			)
		)
		(property "Manufacturer" "Murata"
			(at 311.15 109.22 0)
			(effects
				(font
					(size 1.27 1.27)
					(thickness 0.15)
				)
				(justify left bottom)
				(hide yes)
			)
		)
		(property "MPN" "GRM155R61H104KE14D"
			(at 308.61 109.22 0)
			(effects
				(font
					(size 1.27 1.27)
					(thickness 0.15)
				)
				(justify left bottom)
				(hide yes)
			)
		)
		(property "Val" "100n"
			(at 292.735 128.27 90)
			(effects
				(font
					(size 1.27 1.27)
					(thickness 0.15)
				)
				(justify right)
			)
		)
		(property "License" "Apache-2.0"
			(at 313.69 109.22 0)
			(effects
				(font
					(size 1.27 1.27)
					(thickness 0.15)
				)
				(justify left bottom)
				(hide yes)
			)
		)
		(property "Author" "Antmicro"
			(at 316.23 109.22 0)
			(effects
				(font
					(size 1.27 1.27)
					(thickness 0.15)
				)
				(justify left bottom)
				(hide yes)
			)
		)
		(property "Voltage" "50V"
			(at 318.77 109.22 0)
			(effects
				(font
					(size 1.27 1.27)
				)
				(justify left bottom)
				(hide yes)
			)
		)
		(property "Dielectric" "X5R"
			(at 321.31 109.22 0)
			(effects
				(font
					(size 1.27 1.27)
				)
				(justify left bottom)
				(hide yes)
			)
		)
		(pin "1"
		)
		(pin "2"
		)
		(instances
			(project "jetson-agx-thor-baseboard"
				(path ""
					(reference "C313")
					(unit 1)
				)
			)
		)
	)
	(symbol
		(lib_id "antmicroResistors0402:R_0R_0402")
		(at 342.9 139.7 0)
		(unit 1)
		(exclude_from_sim no)
		(in_bom yes)
		(on_board yes)
		(dnp no)
		(property "Reference" "R403"
			(at 340.868 138.684 0)
			(effects
				(font
					(size 1.27 1.27)
					(thickness 0.15)
				)
			)
		)
		(property "Value" "R_0R_0402"
			(at 363.22 152.4 0)
			(effects
				(font
					(size 1.27 1.27)
					(thickness 0.15)
				)
				(justify left bottom)
				(hide yes)
			)
		)
		(property "Footprint" "antmicro-footprints:R_0402_1005Metric"
			(at 363.22 154.94 0)
			(effects
				(font
					(size 1.27 1.27)
					(thickness 0.15)
				)
				(justify left bottom)
				(hide yes)
			)
		)
		(property "Datasheet" "https://industrial.panasonic.com/cdbs/www-data/pdf/RDA0000/AOA0000C301.pdf"
			(at 363.22 157.48 0)
			(effects
				(font
					(size 1.27 1.27)
					(thickness 0.15)
				)
				(justify left bottom)
				(hide yes)
			)
		)
		(property "Description" "SMD Chip Resistor, Jumper, 0 ohm, 100 mW, 0402 [1005 Metric], Thick Film, General Purpose"
			(at 363.22 172.72 0)
			(effects
				(font
					(size 1.27 1.27)
				)
				(justify left bottom)
				(hide yes)
			)
		)
		(property "MPN" "ERJ2GE0R00X"
			(at 363.22 160.02 0)
			(effects
				(font
					(size 1.27 1.27)
					(thickness 0.15)
				)
				(justify left bottom)
				(hide yes)
			)
		)
		(property "Manufacturer" "Panasonic"
			(at 363.22 162.56 0)
			(effects
				(font
					(size 1.27 1.27)
					(thickness 0.15)
				)
				(justify left bottom)
				(hide yes)
			)
		)
		(property "License" "Apache-2.0"
			(at 363.22 165.1 0)
			(effects
				(font
					(size 1.27 1.27)
					(thickness 0.15)
				)
				(justify left bottom)
				(hide yes)
			)
		)
		(property "Author" "Antmicro"
			(at 363.22 167.64 0)
			(effects
				(font
					(size 1.27 1.27)
					(thickness 0.15)
				)
				(justify left bottom)
				(hide yes)
			)
		)
		(property "Val" "0R"
			(at 348.742 138.684 0)
			(effects
				(font
					(size 1.27 1.27)
					(thickness 0.15)
				)
			)
		)
		(property "Tolerance" "~"
			(at 363.22 149.86 0)
			(effects
				(font
					(size 1.27 1.27)
				)
				(justify left bottom)
				(hide yes)
			)
		)
		(property "Current" "1A"
			(at 363.22 170.18 0)
			(effects
				(font
					(size 1.27 1.27)
					(thickness 0.15)
				)
				(justify left bottom)
				(hide yes)
			)
		)
		(pin "2"
		)
		(pin "1"
		)
		(instances
			(project "jetson-agx-thor-baseboard"
				(path ""
					(reference "R403")
					(unit 1)
				)
			)
		)
	)
	(symbol
		(lib_id "antmicropower:GND")
		(at 290.83 130.81 0)
		(unit 1)
		(exclude_from_sim no)
		(in_bom yes)
		(on_board yes)
		(dnp no)
		(fields_autoplaced yes)
		(property "Reference" "#PWR0646"
			(at 290.83 137.16 0)
			(effects
				(font
					(size 1.27 1.27)
				)
				(justify left bottom)
				(hide yes)
			)
		)
		(property "Value" "GND"
			(at 290.83 134.62 0)
			(effects
				(font
					(size 1.27 1.27)
					(thickness 0.15)
				)
			)
		)
		(property "Footprint" ""
			(at 299.72 138.43 0)
			(effects
				(font
					(size 1.27 1.27)
					(thickness 0.15)
				)
				(justify left bottom)
				(hide yes)
			)
		)
		(property "Datasheet" ""
			(at 299.72 143.51 0)
			(effects
				(font
					(size 1.27 1.27)
					(thickness 0.15)
				)
				(justify left bottom)
				(hide yes)
			)
		)
		(property "Description" ""
			(at 290.83 130.81 0)
			(effects
				(font
					(size 1.27 1.27)
				)
				(hide yes)
			)
		)
		(property "Author" "Antmicro"
			(at 299.72 138.43 0)
			(effects
				(font
					(size 1.27 1.27)
					(thickness 0.15)
				)
				(justify left bottom)
				(hide yes)
			)
		)
		(property "License" "Apache-2.0"
			(at 299.72 140.97 0)
			(effects
				(font
					(size 1.27 1.27)
					(thickness 0.15)
				)
				(justify left bottom)
				(hide yes)
			)
		)
		(pin "1"
		)
		(instances
			(project "jetson-agx-thor-baseboard"
				(path ""
					(reference "#PWR0646")
					(unit 1)
				)
			)
		)
	)
	(symbol
		(lib_id "antmicropower:+1V8")
		(at 204.47 229.87 0)
		(unit 1)
		(exclude_from_sim no)
		(in_bom yes)
		(on_board yes)
		(dnp no)
		(property "Reference" "#PWR0405"
			(at 204.47 233.68 0)
			(effects
				(font
					(size 1.27 1.27)
				)
				(justify left bottom)
				(hide yes)
			)
		)
		(property "Value" "+1V8"
			(at 201.295 226.06 0)
			(effects
				(font
					(size 1.27 1.27)
					(thickness 0.15)
				)
				(justify left)
			)
		)
		(property "Footprint" ""
			(at 219.71 237.49 0)
			(effects
				(font
					(size 1.27 1.27)
					(thickness 0.15)
				)
				(justify left bottom)
				(hide yes)
			)
		)
		(property "Datasheet" ""
			(at 219.71 240.03 0)
			(effects
				(font
					(size 1.27 1.27)
					(thickness 0.15)
				)
				(justify left bottom)
				(hide yes)
			)
		)
		(property "Description" ""
			(at 204.47 229.87 0)
			(effects
				(font
					(size 1.27 1.27)
				)
				(hide yes)
			)
		)
		(property "Author" "Antmicro"
			(at 219.71 234.95 0)
			(effects
				(font
					(size 1.27 1.27)
					(thickness 0.15)
				)
				(justify left bottom)
				(hide yes)
			)
		)
		(property "License" "Apache-2.0"
			(at 219.71 237.49 0)
			(effects
				(font
					(size 1.27 1.27)
					(thickness 0.15)
				)
				(justify left bottom)
				(hide yes)
			)
		)
		(pin "1"
		)
		(instances
			(project "jetson-agx-thor-baseboard"
				(path ""
					(reference "#PWR0405")
					(unit 1)
				)
			)
		)
	)
	(symbol
		(lib_id "antmicropower:+5V")
		(at 73.66 124.46 0)
		(unit 1)
		(exclude_from_sim no)
		(in_bom yes)
		(on_board yes)
		(dnp no)
		(property "Reference" "#PWR0393"
			(at 73.66 128.27 0)
			(effects
				(font
					(size 1.27 1.27)
				)
				(justify left bottom)
				(hide yes)
			)
		)
		(property "Value" "+5V"
			(at 71.755 121.285 0)
			(effects
				(font
					(size 1.27 1.27)
					(thickness 0.15)
				)
				(justify left bottom)
			)
		)
		(property "Footprint" ""
			(at 88.9 132.08 0)
			(effects
				(font
					(size 1.27 1.27)
					(thickness 0.15)
				)
				(justify left bottom)
				(hide yes)
			)
		)
		(property "Datasheet" ""
			(at 88.9 134.62 0)
			(effects
				(font
					(size 1.27 1.27)
					(thickness 0.15)
				)
				(justify left bottom)
				(hide yes)
			)
		)
		(property "Description" ""
			(at 73.66 124.46 0)
			(effects
				(font
					(size 1.27 1.27)
				)
				(hide yes)
			)
		)
		(property "Author" "Antmicro"
			(at 88.9 132.08 0)
			(effects
				(font
					(size 1.27 1.27)
					(thickness 0.15)
				)
				(justify left bottom)
				(hide yes)
			)
		)
		(property "License" "Apache-2.0"
			(at 88.9 134.62 0)
			(effects
				(font
					(size 1.27 1.27)
					(thickness 0.15)
				)
				(justify left bottom)
				(hide yes)
			)
		)
		(pin "1"
		)
		(instances
			(project "jetson-agx-thor-baseboard"
				(path ""
					(reference "#PWR0393")
					(unit 1)
				)
			)
		)
	)
	(symbol
		(lib_id "antmicroWire2BoardConnectors:Molex_PicoBlade_1x4_0533980471")
		(at 118.11 149.86 0)
		(mirror x)
		(unit 1)
		(exclude_from_sim no)
		(in_bom yes)
		(on_board yes)
		(dnp no)
		(fields_autoplaced yes)
		(property "Reference" "J15"
			(at 123.19 130.81 0)
			(effects
				(font
					(size 1.27 1.27)
					(thickness 0.15)
				)
			)
		)
		(property "Value" "Molex_PicoBlade_1x4_0533980471"
			(at 138.43 142.24 0)
			(effects
				(font
					(size 1.27 1.27)
					(thickness 0.15)
				)
				(justify left bottom)
				(hide yes)
			)
		)
		(property "Footprint" "antmicro-footprints:Conn_Molex_PicoBlade_1x4_0533980471"
			(at 138.43 139.7 0)
			(effects
				(font
					(size 1.27 1.27)
					(thickness 0.15)
				)
				(justify left bottom)
				(hide yes)
			)
		)
		(property "Datasheet" "https://www.molex.com/molex/products/part-detail/pcb_headers/0533980471"
			(at 138.43 137.16 0)
			(effects
				(font
					(size 1.27 1.27)
					(thickness 0.15)
				)
				(justify left bottom)
				(hide yes)
			)
		)
		(property "Description" "Pin Header, Vertical, Signal, 1.25 mm, 1 Rows, 4 Contacts, Surface Mount Straight"
			(at 118.11 149.86 0)
			(effects
				(font
					(size 1.27 1.27)
				)
				(hide yes)
			)
		)
		(property "MPN" "0533980471"
			(at 123.19 133.35 0)
			(effects
				(font
					(size 1.27 1.27)
					(thickness 0.15)
				)
			)
		)
		(property "Manufacturer" "Molex"
			(at 138.43 134.62 0)
			(effects
				(font
					(size 1.27 1.27)
					(thickness 0.15)
				)
				(justify left bottom)
				(hide yes)
			)
		)
		(property "Author" "Antmicro"
			(at 138.43 129.54 0)
			(effects
				(font
					(size 1.27 1.27)
					(thickness 0.15)
				)
				(justify left bottom)
				(hide yes)
			)
		)
		(property "License" "Apache-2.0"
			(at 138.43 127 0)
			(effects
				(font
					(size 1.27 1.27)
					(thickness 0.15)
				)
				(justify left bottom)
				(hide yes)
			)
		)
		(pin "1"
		)
		(pin "2"
		)
		(pin "3"
		)
		(pin "4"
		)
		(pin "MP1"
		)
		(pin "MP2"
		)
		(instances
			(project "jetson-agx-thor-baseboard"
				(path ""
					(reference "J15")
					(unit 1)
				)
			)
		)
	)
	(symbol
		(lib_id "antmicropower:GND")
		(at 95.25 135.89 0)
		(unit 1)
		(exclude_from_sim no)
		(in_bom yes)
		(on_board yes)
		(dnp no)
		(fields_autoplaced yes)
		(property "Reference" "#PWR0131"
			(at 95.25 142.24 0)
			(effects
				(font
					(size 1.27 1.27)
				)
				(justify left bottom)
				(hide yes)
			)
		)
		(property "Value" "GND"
			(at 95.25 139.7 0)
			(effects
				(font
					(size 1.27 1.27)
					(thickness 0.15)
				)
			)
		)
		(property "Footprint" ""
			(at 104.14 143.51 0)
			(effects
				(font
					(size 1.27 1.27)
					(thickness 0.15)
				)
				(justify left bottom)
				(hide yes)
			)
		)
		(property "Datasheet" ""
			(at 104.14 148.59 0)
			(effects
				(font
					(size 1.27 1.27)
					(thickness 0.15)
				)
				(justify left bottom)
				(hide yes)
			)
		)
		(property "Description" ""
			(at 95.25 135.89 0)
			(effects
				(font
					(size 1.27 1.27)
				)
				(hide yes)
			)
		)
		(property "Author" "Antmicro"
			(at 104.14 143.51 0)
			(effects
				(font
					(size 1.27 1.27)
					(thickness 0.15)
				)
				(justify left bottom)
				(hide yes)
			)
		)
		(property "License" "Apache-2.0"
			(at 104.14 146.05 0)
			(effects
				(font
					(size 1.27 1.27)
					(thickness 0.15)
				)
				(justify left bottom)
				(hide yes)
			)
		)
		(pin "1"
		)
		(instances
			(project "jetson-agx-thor-baseboard"
				(path ""
					(reference "#PWR0131")
					(unit 1)
				)
			)
		)
	)
	(symbol
		(lib_id "antmicropower:GND")
		(at 57.15 78.74 0)
		(unit 1)
		(exclude_from_sim no)
		(in_bom yes)
		(on_board yes)
		(dnp no)
		(fields_autoplaced yes)
		(property "Reference" "#PWR0123"
			(at 57.15 85.09 0)
			(effects
				(font
					(size 1.27 1.27)
				)
				(justify left bottom)
				(hide yes)
			)
		)
		(property "Value" "GND"
			(at 57.15 82.55 0)
			(effects
				(font
					(size 1.27 1.27)
					(thickness 0.15)
				)
			)
		)
		(property "Footprint" ""
			(at 66.04 86.36 0)
			(effects
				(font
					(size 1.27 1.27)
					(thickness 0.15)
				)
				(justify left bottom)
				(hide yes)
			)
		)
		(property "Datasheet" ""
			(at 66.04 91.44 0)
			(effects
				(font
					(size 1.27 1.27)
					(thickness 0.15)
				)
				(justify left bottom)
				(hide yes)
			)
		)
		(property "Description" ""
			(at 57.15 78.74 0)
			(effects
				(font
					(size 1.27 1.27)
				)
				(hide yes)
			)
		)
		(property "Author" "Antmicro"
			(at 66.04 86.36 0)
			(effects
				(font
					(size 1.27 1.27)
					(thickness 0.15)
				)
				(justify left bottom)
				(hide yes)
			)
		)
		(property "License" "Apache-2.0"
			(at 66.04 88.9 0)
			(effects
				(font
					(size 1.27 1.27)
					(thickness 0.15)
				)
				(justify left bottom)
				(hide yes)
			)
		)
		(pin "1"
		)
		(instances
			(project "jetson-agx-thor-baseboard"
				(path ""
					(reference "#PWR0123")
					(unit 1)
				)
			)
		)
	)
	(symbol
		(lib_id "antmicroCapacitors0402:C_100n_0402")
		(at 175.26 39.37 90)
		(mirror x)
		(unit 1)
		(exclude_from_sim no)
		(in_bom yes)
		(on_board yes)
		(dnp no)
		(property "Reference" "C208"
			(at 177.165 40.64 90)
			(effects
				(font
					(size 1.27 1.27)
				)
				(justify right)
			)
		)
		(property "Value" "C_100n_0402"
			(at 185.42 59.69 0)
			(effects
				(font
					(size 1.27 1.27)
					(thickness 0.15)
				)
				(justify left bottom)
				(hide yes)
			)
		)
		(property "Footprint" "antmicro-footprints:C_0402_1005Metric"
			(at 187.96 59.69 0)
			(effects
				(font
					(size 1.27 1.27)
					(thickness 0.15)
				)
				(justify left bottom)
				(hide yes)
			)
		)
		(property "Datasheet" "https://www.murata.com/products/productdetail?partno=GRM155R61H104KE14%23"
			(at 190.5 59.69 0)
			(effects
				(font
					(size 1.27 1.27)
					(thickness 0.15)
				)
				(justify left bottom)
				(hide yes)
			)
		)
		(property "Description" "SMD Multilayer Ceramic Capacitor, 0.1 µF, 50 V, 0402 [1005 Metric], ± 10%, X5R, GRM Series"
			(at 175.26 39.37 0)
			(effects
				(font
					(size 1.27 1.27)
				)
				(hide yes)
			)
		)
		(property "Manufacturer" "Murata"
			(at 195.58 59.69 0)
			(effects
				(font
					(size 1.27 1.27)
					(thickness 0.15)
				)
				(justify left bottom)
				(hide yes)
			)
		)
		(property "MPN" "GRM155R61H104KE14D"
			(at 193.04 59.69 0)
			(effects
				(font
					(size 1.27 1.27)
					(thickness 0.15)
				)
				(justify left bottom)
				(hide yes)
			)
		)
		(property "Val" "100n"
			(at 177.165 43.18 90)
			(effects
				(font
					(size 1.27 1.27)
					(thickness 0.15)
				)
				(justify right)
			)
		)
		(property "License" "Apache-2.0"
			(at 198.12 59.69 0)
			(effects
				(font
					(size 1.27 1.27)
					(thickness 0.15)
				)
				(justify left bottom)
				(hide yes)
			)
		)
		(property "Author" "Antmicro"
			(at 200.66 59.69 0)
			(effects
				(font
					(size 1.27 1.27)
					(thickness 0.15)
				)
				(justify left bottom)
				(hide yes)
			)
		)
		(property "Voltage" "50V"
			(at 203.2 59.69 0)
			(effects
				(font
					(size 1.27 1.27)
				)
				(justify left bottom)
				(hide yes)
			)
		)
		(property "Dielectric" "X5R"
			(at 205.74 59.69 0)
			(effects
				(font
					(size 1.27 1.27)
				)
				(justify left bottom)
				(hide yes)
			)
		)
		(pin "1"
		)
		(pin "2"
		)
		(instances
			(project "jetson-agx-thor-baseboard"
				(path ""
					(reference "C208")
					(unit 1)
				)
			)
		)
	)
	(symbol
		(lib_id "antmicropower:GND")
		(at 227.33 66.04 0)
		(unit 1)
		(exclude_from_sim no)
		(in_bom yes)
		(on_board yes)
		(dnp no)
		(fields_autoplaced yes)
		(property "Reference" "#PWR0414"
			(at 227.33 72.39 0)
			(effects
				(font
					(size 1.27 1.27)
				)
				(justify left bottom)
				(hide yes)
			)
		)
		(property "Value" "GND"
			(at 227.33 69.85 0)
			(effects
				(font
					(size 1.27 1.27)
					(thickness 0.15)
				)
			)
		)
		(property "Footprint" ""
			(at 236.22 73.66 0)
			(effects
				(font
					(size 1.27 1.27)
					(thickness 0.15)
				)
				(justify left bottom)
				(hide yes)
			)
		)
		(property "Datasheet" ""
			(at 236.22 78.74 0)
			(effects
				(font
					(size 1.27 1.27)
					(thickness 0.15)
				)
				(justify left bottom)
				(hide yes)
			)
		)
		(property "Description" ""
			(at 227.33 66.04 0)
			(effects
				(font
					(size 1.27 1.27)
				)
				(hide yes)
			)
		)
		(property "Author" "Antmicro"
			(at 236.22 73.66 0)
			(effects
				(font
					(size 1.27 1.27)
					(thickness 0.15)
				)
				(justify left bottom)
				(hide yes)
			)
		)
		(property "License" "Apache-2.0"
			(at 236.22 76.2 0)
			(effects
				(font
					(size 1.27 1.27)
					(thickness 0.15)
				)
				(justify left bottom)
				(hide yes)
			)
		)
		(pin "1"
		)
		(instances
			(project "jetson-agx-thor-baseboard"
				(path ""
					(reference "#PWR0414")
					(unit 1)
				)
			)
		)
	)
	(symbol
		(lib_id "antmicroTestPoints:TP_0.75mm_SMD")
		(at 364.49 142.24 0)
		(unit 1)
		(exclude_from_sim no)
		(in_bom no)
		(on_board yes)
		(dnp no)
		(property "Reference" "TP96"
			(at 368.554 142.24 0)
			(effects
				(font
					(size 1.27 1.27)
					(thickness 0.15)
				)
				(justify left)
			)
		)
		(property "Value" "TP_0.75mm_SMD"
			(at 374.65 146.05 0)
			(effects
				(font
					(size 1.27 1.27)
					(thickness 0.15)
				)
				(justify left bottom)
				(hide yes)
			)
		)
		(property "Footprint" "antmicro-footprints:TP_SMD_0.75mm"
			(at 374.65 148.59 0)
			(effects
				(font
					(size 1.27 1.27)
					(thickness 0.15)
				)
				(justify left bottom)
				(hide yes)
			)
		)
		(property "Datasheet" ""
			(at 382.27 154.94 0)
			(effects
				(font
					(size 1.27 1.27)
					(thickness 0.15)
				)
				(justify left bottom)
				(hide yes)
			)
		)
		(property "Description" "SMT test point"
			(at 364.49 142.24 0)
			(effects
				(font
					(size 1.27 1.27)
				)
				(hide yes)
			)
		)
		(property "MPN" ""
			(at 375.285 153.67 0)
			(effects
				(font
					(size 1.27 1.27)
					(thickness 0.15)
				)
				(justify left bottom)
				(hide yes)
			)
		)
		(property "Manufacturer" ""
			(at 375.285 148.59 0)
			(effects
				(font
					(size 1.27 1.27)
					(thickness 0.15)
				)
				(justify left bottom)
				(hide yes)
			)
		)
		(property "Author" "Antmicro"
			(at 374.65 151.13 0)
			(effects
				(font
					(size 1.27 1.27)
					(thickness 0.15)
				)
				(justify left bottom)
				(hide yes)
			)
		)
		(property "License" "Apache-2.0"
			(at 374.65 153.67 0)
			(effects
				(font
					(size 1.27 1.27)
					(thickness 0.15)
				)
				(justify left bottom)
				(hide yes)
			)
		)
		(pin "1"
		)
		(instances
			(project "jetson-agx-thor-baseboard"
				(path ""
					(reference "TP96")
					(unit 1)
				)
			)
		)
	)
	(symbol
		(lib_id "antmicropower:GND")
		(at 303.53 90.17 0)
		(unit 1)
		(exclude_from_sim no)
		(in_bom yes)
		(on_board yes)
		(dnp no)
		(property "Reference" "#PWR0409"
			(at 303.53 96.52 0)
			(effects
				(font
					(size 1.27 1.27)
				)
				(justify left bottom)
				(hide yes)
			)
		)
		(property "Value" "GND"
			(at 303.53 93.98 0)
			(effects
				(font
					(size 1.27 1.27)
					(thickness 0.15)
				)
			)
		)
		(property "Footprint" ""
			(at 312.42 97.79 0)
			(effects
				(font
					(size 1.27 1.27)
					(thickness 0.15)
				)
				(justify left bottom)
				(hide yes)
			)
		)
		(property "Datasheet" ""
			(at 312.42 102.87 0)
			(effects
				(font
					(size 1.27 1.27)
					(thickness 0.15)
				)
				(justify left bottom)
				(hide yes)
			)
		)
		(property "Description" ""
			(at 303.53 90.17 0)
			(effects
				(font
					(size 1.27 1.27)
				)
				(hide yes)
			)
		)
		(property "Author" "Antmicro"
			(at 312.42 97.79 0)
			(effects
				(font
					(size 1.27 1.27)
					(thickness 0.15)
				)
				(justify left bottom)
				(hide yes)
			)
		)
		(property "License" "Apache-2.0"
			(at 312.42 100.33 0)
			(effects
				(font
					(size 1.27 1.27)
					(thickness 0.15)
				)
				(justify left bottom)
				(hide yes)
			)
		)
		(pin "1"
		)
		(instances
			(project "jetson-agx-thor-baseboard"
				(path ""
					(reference "#PWR0409")
					(unit 1)
				)
			)
		)
	)
	(symbol
		(lib_id "antmicroTVSDiodes:PESD5Z5_0F")
		(at 88.9 129.54 90)
		(mirror x)
		(unit 1)
		(exclude_from_sim no)
		(in_bom yes)
		(on_board yes)
		(dnp no)
		(property "Reference" "D39"
			(at 92.964 130.302 90)
			(effects
				(font
					(size 1.27 1.27)
				)
				(justify left)
			)
		)
		(property "Value" "PESD5Z5.0F"
			(at 104.14 151.13 0)
			(effects
				(font
					(size 1.27 1.27)
					(thickness 0.15)
				)
				(justify left bottom)
				(hide yes)
			)
		)
		(property "Footprint" "antmicro-footprints:SOD-523"
			(at 93.98 144.78 0)
			(effects
				(font
					(size 1.27 1.27)
					(thickness 0.15)
				)
				(justify left bottom)
				(hide yes)
			)
		)
		(property "Datasheet" "https://assets.nexperia.com/documents/data-sheet/PESD5Z5_0.pdf"
			(at 96.52 144.78 0)
			(effects
				(font
					(size 1.27 1.27)
					(thickness 0.15)
				)
				(justify left bottom)
				(hide yes)
			)
		)
		(property "Description" "Unidirectional TVS, 30 kV,  SOD-523, 5 V, 89 pF"
			(at 109.22 144.78 0)
			(effects
				(font
					(size 1.27 1.27)
				)
				(justify left bottom)
				(hide yes)
			)
		)
		(property "Manufacturer" "Nexperia"
			(at 99.06 144.78 0)
			(effects
				(font
					(size 1.27 1.27)
					(thickness 0.15)
				)
				(justify left bottom)
				(hide yes)
			)
		)
		(property "MPN" "PESD5Z5.0F"
			(at 87.122 127.254 0)
			(effects
				(font
					(size 1.27 1.27)
					(thickness 0.15)
				)
				(justify left bottom)
			)
		)
		(property "Author" "Antmicro"
			(at 104.14 144.78 0)
			(effects
				(font
					(size 1.27 1.27)
					(thickness 0.15)
				)
				(justify left bottom)
				(hide yes)
			)
		)
		(property "License" "Apache-2.0"
			(at 106.68 144.78 0)
			(effects
				(font
					(size 1.27 1.27)
					(thickness 0.15)
				)
				(justify left bottom)
				(hide yes)
			)
		)
		(pin "1"
		)
		(pin "2"
		)
		(instances
			(project "jetson-agx-thor-baseboard"
				(path ""
					(reference "D39")
					(unit 1)
				)
			)
		)
	)
	(symbol
		(lib_id "antmicropower:GND")
		(at 240.03 86.36 0)
		(unit 1)
		(exclude_from_sim no)
		(in_bom yes)
		(on_board yes)
		(dnp no)
		(fields_autoplaced yes)
		(property "Reference" "#PWR0417"
			(at 240.03 92.71 0)
			(effects
				(font
					(size 1.27 1.27)
				)
				(justify left bottom)
				(hide yes)
			)
		)
		(property "Value" "GND"
			(at 240.03 90.17 0)
			(effects
				(font
					(size 1.27 1.27)
					(thickness 0.15)
				)
			)
		)
		(property "Footprint" ""
			(at 248.92 93.98 0)
			(effects
				(font
					(size 1.27 1.27)
					(thickness 0.15)
				)
				(justify left bottom)
				(hide yes)
			)
		)
		(property "Datasheet" ""
			(at 248.92 99.06 0)
			(effects
				(font
					(size 1.27 1.27)
					(thickness 0.15)
				)
				(justify left bottom)
				(hide yes)
			)
		)
		(property "Description" ""
			(at 240.03 86.36 0)
			(effects
				(font
					(size 1.27 1.27)
				)
				(hide yes)
			)
		)
		(property "Author" "Antmicro"
			(at 248.92 93.98 0)
			(effects
				(font
					(size 1.27 1.27)
					(thickness 0.15)
				)
				(justify left bottom)
				(hide yes)
			)
		)
		(property "License" "Apache-2.0"
			(at 248.92 96.52 0)
			(effects
				(font
					(size 1.27 1.27)
					(thickness 0.15)
				)
				(justify left bottom)
				(hide yes)
			)
		)
		(pin "1"
		)
		(instances
			(project "jetson-agx-thor-baseboard"
				(path ""
					(reference "#PWR0417")
					(unit 1)
				)
			)
		)
	)
	(symbol
		(lib_id "antmicroTVSDiodes:TPD1E0B04_XDFN-2")
		(at 204.47 246.38 90)
		(unit 1)
		(exclude_from_sim no)
		(in_bom yes)
		(on_board yes)
		(dnp no)
		(property "Reference" "D38"
			(at 202.565 242.57 90)
			(effects
				(font
					(size 1.27 1.27)
				)
				(justify left)
			)
		)
		(property "Value" "TPD1E0B04_XDFN-2"
			(at 214.63 231.14 0)
			(effects
				(font
					(size 1.27 1.27)
					(thickness 0.15)
				)
				(justify left bottom)
				(hide yes)
			)
		)
		(property "Footprint" "antmicro-footprints:XDFN-2_1x0.60mm"
			(at 209.55 231.14 0)
			(effects
				(font
					(size 1.27 1.27)
					(thickness 0.15)
				)
				(justify left bottom)
				(hide yes)
			)
		)
		(property "Datasheet" "https://www.ti.com/general/docs/suppproductinfo.tsp?distId=26&gotoUrl=https://www.ti.com/lit/gpn/tpd1e0b04"
			(at 212.09 231.14 0)
			(effects
				(font
					(size 1.27 1.27)
					(thickness 0.15)
				)
				(justify left bottom)
				(hide yes)
			)
		)
		(property "Description" "Bidirectional TVS, 8 kV,  XDFN-2, 3.6 V, 0.18 pF"
			(at 204.47 246.38 0)
			(effects
				(font
					(size 1.27 1.27)
				)
				(hide yes)
			)
		)
		(property "Manufacturer" "Texas Instruments"
			(at 217.17 231.14 0)
			(effects
				(font
					(size 1.27 1.27)
					(thickness 0.15)
				)
				(justify left bottom)
				(hide yes)
			)
		)
		(property "MPN" "TPD1E0B04DPYR"
			(at 202.565 245.11 90)
			(effects
				(font
					(size 1.27 1.27)
					(thickness 0.15)
				)
				(justify left)
			)
		)
		(property "Author" "Antmicro"
			(at 219.71 231.14 0)
			(effects
				(font
					(size 1.27 1.27)
					(thickness 0.15)
				)
				(justify left bottom)
				(hide yes)
			)
		)
		(property "License" "Apache-2.0"
			(at 222.25 231.14 0)
			(effects
				(font
					(size 1.27 1.27)
					(thickness 0.15)
				)
				(justify left bottom)
				(hide yes)
			)
		)
		(pin "1"
		)
		(pin "2"
		)
		(instances
			(project "jetson-agx-thor-baseboard"
				(path ""
					(reference "D38")
					(unit 1)
				)
			)
		)
	)
	(symbol
		(lib_id "antmicroResistors0402:R_0R_0402")
		(at 342.9 142.24 0)
		(unit 1)
		(exclude_from_sim no)
		(in_bom yes)
		(on_board yes)
		(dnp no)
		(property "Reference" "R404"
			(at 340.868 141.224 0)
			(effects
				(font
					(size 1.27 1.27)
					(thickness 0.15)
				)
			)
		)
		(property "Value" "R_0R_0402"
			(at 363.22 154.94 0)
			(effects
				(font
					(size 1.27 1.27)
					(thickness 0.15)
				)
				(justify left bottom)
				(hide yes)
			)
		)
		(property "Footprint" "antmicro-footprints:R_0402_1005Metric"
			(at 363.22 157.48 0)
			(effects
				(font
					(size 1.27 1.27)
					(thickness 0.15)
				)
				(justify left bottom)
				(hide yes)
			)
		)
		(property "Datasheet" "https://industrial.panasonic.com/cdbs/www-data/pdf/RDA0000/AOA0000C301.pdf"
			(at 363.22 160.02 0)
			(effects
				(font
					(size 1.27 1.27)
					(thickness 0.15)
				)
				(justify left bottom)
				(hide yes)
			)
		)
		(property "Description" "SMD Chip Resistor, Jumper, 0 ohm, 100 mW, 0402 [1005 Metric], Thick Film, General Purpose"
			(at 363.22 175.26 0)
			(effects
				(font
					(size 1.27 1.27)
				)
				(justify left bottom)
				(hide yes)
			)
		)
		(property "MPN" "ERJ2GE0R00X"
			(at 363.22 162.56 0)
			(effects
				(font
					(size 1.27 1.27)
					(thickness 0.15)
				)
				(justify left bottom)
				(hide yes)
			)
		)
		(property "Manufacturer" "Panasonic"
			(at 363.22 165.1 0)
			(effects
				(font
					(size 1.27 1.27)
					(thickness 0.15)
				)
				(justify left bottom)
				(hide yes)
			)
		)
		(property "License" "Apache-2.0"
			(at 363.22 167.64 0)
			(effects
				(font
					(size 1.27 1.27)
					(thickness 0.15)
				)
				(justify left bottom)
				(hide yes)
			)
		)
		(property "Author" "Antmicro"
			(at 363.22 170.18 0)
			(effects
				(font
					(size 1.27 1.27)
					(thickness 0.15)
				)
				(justify left bottom)
				(hide yes)
			)
		)
		(property "Val" "0R"
			(at 348.742 141.224 0)
			(effects
				(font
					(size 1.27 1.27)
					(thickness 0.15)
				)
			)
		)
		(property "Tolerance" "~"
			(at 363.22 152.4 0)
			(effects
				(font
					(size 1.27 1.27)
				)
				(justify left bottom)
				(hide yes)
			)
		)
		(property "Current" "1A"
			(at 363.22 172.72 0)
			(effects
				(font
					(size 1.27 1.27)
					(thickness 0.15)
				)
				(justify left bottom)
				(hide yes)
			)
		)
		(pin "2"
		)
		(pin "1"
		)
		(instances
			(project "jetson-agx-thor-baseboard"
				(path ""
					(reference "R404")
					(unit 1)
				)
			)
		)
	)
	(symbol
		(lib_id "antmicropower:+3V3")
		(at 175.26 36.83 0)
		(unit 1)
		(exclude_from_sim no)
		(in_bom yes)
		(on_board yes)
		(dnp no)
		(property "Reference" "#PWR0401"
			(at 175.26 40.64 0)
			(effects
				(font
					(size 1.27 1.27)
				)
				(justify left bottom)
				(hide yes)
			)
		)
		(property "Value" "+3V3"
			(at 172.085 33.02 0)
			(effects
				(font
					(size 1.27 1.27)
					(thickness 0.15)
				)
				(justify left)
			)
		)
		(property "Footprint" ""
			(at 190.5 44.45 0)
			(effects
				(font
					(size 1.27 1.27)
					(thickness 0.15)
				)
				(justify left bottom)
				(hide yes)
			)
		)
		(property "Datasheet" ""
			(at 190.5 46.99 0)
			(effects
				(font
					(size 1.27 1.27)
					(thickness 0.15)
				)
				(justify left bottom)
				(hide yes)
			)
		)
		(property "Description" ""
			(at 175.26 36.83 0)
			(effects
				(font
					(size 1.27 1.27)
				)
				(hide yes)
			)
		)
		(property "Author" "Antmicro"
			(at 190.5 39.37 0)
			(effects
				(font
					(size 1.27 1.27)
					(thickness 0.15)
				)
				(justify left bottom)
				(hide yes)
			)
		)
		(property "License" "Apache-2.0"
			(at 190.5 41.91 0)
			(effects
				(font
					(size 1.27 1.27)
					(thickness 0.15)
				)
				(justify left bottom)
				(hide yes)
			)
		)
		(pin "1"
		)
		(instances
			(project "jetson-agx-thor-baseboard"
				(path ""
					(reference "#PWR0401")
					(unit 1)
				)
			)
		)
	)
	(symbol
		(lib_id "antmicroTestPoints:TP_0.75mm_SMD")
		(at 364.49 139.7 0)
		(unit 1)
		(exclude_from_sim no)
		(in_bom no)
		(on_board yes)
		(dnp no)
		(property "Reference" "TP95"
			(at 368.554 139.7 0)
			(effects
				(font
					(size 1.27 1.27)
					(thickness 0.15)
				)
				(justify left)
			)
		)
		(property "Value" "TP_0.75mm_SMD"
			(at 374.65 143.51 0)
			(effects
				(font
					(size 1.27 1.27)
					(thickness 0.15)
				)
				(justify left bottom)
				(hide yes)
			)
		)
		(property "Footprint" "antmicro-footprints:TP_SMD_0.75mm"
			(at 374.65 146.05 0)
			(effects
				(font
					(size 1.27 1.27)
					(thickness 0.15)
				)
				(justify left bottom)
				(hide yes)
			)
		)
		(property "Datasheet" ""
			(at 382.27 152.4 0)
			(effects
				(font
					(size 1.27 1.27)
					(thickness 0.15)
				)
				(justify left bottom)
				(hide yes)
			)
		)
		(property "Description" "SMT test point"
			(at 364.49 139.7 0)
			(effects
				(font
					(size 1.27 1.27)
				)
				(hide yes)
			)
		)
		(property "MPN" ""
			(at 375.285 151.13 0)
			(effects
				(font
					(size 1.27 1.27)
					(thickness 0.15)
				)
				(justify left bottom)
				(hide yes)
			)
		)
		(property "Manufacturer" ""
			(at 375.285 146.05 0)
			(effects
				(font
					(size 1.27 1.27)
					(thickness 0.15)
				)
				(justify left bottom)
				(hide yes)
			)
		)
		(property "Author" "Antmicro"
			(at 374.65 148.59 0)
			(effects
				(font
					(size 1.27 1.27)
					(thickness 0.15)
				)
				(justify left bottom)
				(hide yes)
			)
		)
		(property "License" "Apache-2.0"
			(at 374.65 151.13 0)
			(effects
				(font
					(size 1.27 1.27)
					(thickness 0.15)
				)
				(justify left bottom)
				(hide yes)
			)
		)
		(pin "1"
		)
		(instances
			(project "jetson-agx-thor-baseboard"
				(path ""
					(reference "TP95")
					(unit 1)
				)
			)
		)
	)
	(symbol
		(lib_id "antmicropower:GND")
		(at 300.99 59.69 0)
		(unit 1)
		(exclude_from_sim no)
		(in_bom yes)
		(on_board yes)
		(dnp no)
		(fields_autoplaced yes)
		(property "Reference" "#PWR0422"
			(at 300.99 66.04 0)
			(effects
				(font
					(size 1.27 1.27)
				)
				(justify left bottom)
				(hide yes)
			)
		)
		(property "Value" "GND"
			(at 300.99 63.5 0)
			(effects
				(font
					(size 1.27 1.27)
					(thickness 0.15)
				)
			)
		)
		(property "Footprint" ""
			(at 309.88 67.31 0)
			(effects
				(font
					(size 1.27 1.27)
					(thickness 0.15)
				)
				(justify left bottom)
				(hide yes)
			)
		)
		(property "Datasheet" ""
			(at 309.88 72.39 0)
			(effects
				(font
					(size 1.27 1.27)
					(thickness 0.15)
				)
				(justify left bottom)
				(hide yes)
			)
		)
		(property "Description" ""
			(at 300.99 59.69 0)
			(effects
				(font
					(size 1.27 1.27)
				)
				(hide yes)
			)
		)
		(property "Author" "Antmicro"
			(at 309.88 67.31 0)
			(effects
				(font
					(size 1.27 1.27)
					(thickness 0.15)
				)
				(justify left bottom)
				(hide yes)
			)
		)
		(property "License" "Apache-2.0"
			(at 309.88 69.85 0)
			(effects
				(font
					(size 1.27 1.27)
					(thickness 0.15)
				)
				(justify left bottom)
				(hide yes)
			)
		)
		(pin "1"
		)
		(instances
			(project "jetson-agx-thor-baseboard"
				(path ""
					(reference "#PWR0422")
					(unit 1)
				)
			)
		)
	)
	(symbol
		(lib_id "antmicroTestPoints:TP_0.75mm_SMD")
		(at 191.77 138.43 90)
		(unit 1)
		(exclude_from_sim no)
		(in_bom no)
		(on_board yes)
		(dnp no)
		(property "Reference" "TP87"
			(at 190.754 135.382 90)
			(effects
				(font
					(size 1.27 1.27)
					(thickness 0.15)
				)
				(justify left)
			)
		)
		(property "Value" "TP_0.75mm_SMD"
			(at 195.58 128.27 0)
			(effects
				(font
					(size 1.27 1.27)
					(thickness 0.15)
				)
				(justify left bottom)
				(hide yes)
			)
		)
		(property "Footprint" "antmicro-footprints:TP_SMD_0.75mm"
			(at 198.12 128.27 0)
			(effects
				(font
					(size 1.27 1.27)
					(thickness 0.15)
				)
				(justify left bottom)
				(hide yes)
			)
		)
		(property "Datasheet" ""
			(at 204.47 120.65 0)
			(effects
				(font
					(size 1.27 1.27)
					(thickness 0.15)
				)
				(justify left bottom)
				(hide yes)
			)
		)
		(property "Description" "SMT test point"
			(at 191.77 138.43 0)
			(effects
				(font
					(size 1.27 1.27)
				)
				(hide yes)
			)
		)
		(property "MPN" ""
			(at 203.2 127.635 0)
			(effects
				(font
					(size 1.27 1.27)
					(thickness 0.15)
				)
				(justify left bottom)
				(hide yes)
			)
		)
		(property "Manufacturer" ""
			(at 198.12 127.635 0)
			(effects
				(font
					(size 1.27 1.27)
					(thickness 0.15)
				)
				(justify left bottom)
				(hide yes)
			)
		)
		(property "Author" "Antmicro"
			(at 200.66 128.27 0)
			(effects
				(font
					(size 1.27 1.27)
					(thickness 0.15)
				)
				(justify left bottom)
				(hide yes)
			)
		)
		(property "License" "Apache-2.0"
			(at 203.2 128.27 0)
			(effects
				(font
					(size 1.27 1.27)
					(thickness 0.15)
				)
				(justify left bottom)
				(hide yes)
			)
		)
		(pin "1"
		)
		(instances
			(project "jetson-agx-thor-baseboard"
				(path ""
					(reference "TP87")
					(unit 1)
				)
			)
		)
	)
	(symbol
		(lib_id "antmicropower:GND")
		(at 67.31 38.1 0)
		(unit 1)
		(exclude_from_sim no)
		(in_bom yes)
		(on_board yes)
		(dnp no)
		(fields_autoplaced yes)
		(property "Reference" "#PWR0117"
			(at 67.31 44.45 0)
			(effects
				(font
					(size 1.27 1.27)
				)
				(justify left bottom)
				(hide yes)
			)
		)
		(property "Value" "GND"
			(at 67.31 41.91 0)
			(effects
				(font
					(size 1.27 1.27)
					(thickness 0.15)
				)
			)
		)
		(property "Footprint" ""
			(at 76.2 45.72 0)
			(effects
				(font
					(size 1.27 1.27)
					(thickness 0.15)
				)
				(justify left bottom)
				(hide yes)
			)
		)
		(property "Datasheet" ""
			(at 76.2 50.8 0)
			(effects
				(font
					(size 1.27 1.27)
					(thickness 0.15)
				)
				(justify left bottom)
				(hide yes)
			)
		)
		(property "Description" ""
			(at 67.31 38.1 0)
			(effects
				(font
					(size 1.27 1.27)
				)
				(hide yes)
			)
		)
		(property "Author" "Antmicro"
			(at 76.2 45.72 0)
			(effects
				(font
					(size 1.27 1.27)
					(thickness 0.15)
				)
				(justify left bottom)
				(hide yes)
			)
		)
		(property "License" "Apache-2.0"
			(at 76.2 48.26 0)
			(effects
				(font
					(size 1.27 1.27)
					(thickness 0.15)
				)
				(justify left bottom)
				(hide yes)
			)
		)
		(pin "1"
		)
		(instances
			(project "jetson-agx-thor-baseboard"
				(path ""
					(reference "#PWR0117")
					(unit 1)
				)
			)
		)
	)
	(symbol
		(lib_id "antmicropower:GND")
		(at 175.26 45.72 0)
		(unit 1)
		(exclude_from_sim no)
		(in_bom yes)
		(on_board yes)
		(dnp no)
		(fields_autoplaced yes)
		(property "Reference" "#PWR0402"
			(at 175.26 52.07 0)
			(effects
				(font
					(size 1.27 1.27)
				)
				(justify left bottom)
				(hide yes)
			)
		)
		(property "Value" "GND"
			(at 175.26 49.53 0)
			(effects
				(font
					(size 1.27 1.27)
					(thickness 0.15)
				)
			)
		)
		(property "Footprint" ""
			(at 184.15 53.34 0)
			(effects
				(font
					(size 1.27 1.27)
					(thickness 0.15)
				)
				(justify left bottom)
				(hide yes)
			)
		)
		(property "Datasheet" ""
			(at 184.15 58.42 0)
			(effects
				(font
					(size 1.27 1.27)
					(thickness 0.15)
				)
				(justify left bottom)
				(hide yes)
			)
		)
		(property "Description" ""
			(at 175.26 45.72 0)
			(effects
				(font
					(size 1.27 1.27)
				)
				(hide yes)
			)
		)
		(property "Author" "Antmicro"
			(at 184.15 53.34 0)
			(effects
				(font
					(size 1.27 1.27)
					(thickness 0.15)
				)
				(justify left bottom)
				(hide yes)
			)
		)
		(property "License" "Apache-2.0"
			(at 184.15 55.88 0)
			(effects
				(font
					(size 1.27 1.27)
					(thickness 0.15)
				)
				(justify left bottom)
				(hide yes)
			)
		)
		(pin "1"
		)
		(instances
			(project "jetson-agx-thor-baseboard"
				(path ""
					(reference "#PWR0402")
					(unit 1)
				)
			)
		)
	)
	(symbol
		(lib_id "antmicropower:+5V")
		(at 86.36 123.19 0)
		(unit 1)
		(exclude_from_sim no)
		(in_bom yes)
		(on_board yes)
		(dnp no)
		(property "Reference" "#PWR073"
			(at 86.36 127 0)
			(effects
				(font
					(size 1.27 1.27)
				)
				(justify left bottom)
				(hide yes)
			)
		)
		(property "Value" "+5V"
			(at 84.455 120.015 0)
			(effects
				(font
					(size 1.27 1.27)
					(thickness 0.15)
				)
				(justify left bottom)
			)
		)
		(property "Footprint" ""
			(at 101.6 130.81 0)
			(effects
				(font
					(size 1.27 1.27)
					(thickness 0.15)
				)
				(justify left bottom)
				(hide yes)
			)
		)
		(property "Datasheet" ""
			(at 101.6 133.35 0)
			(effects
				(font
					(size 1.27 1.27)
					(thickness 0.15)
				)
				(justify left bottom)
				(hide yes)
			)
		)
		(property "Description" ""
			(at 86.36 123.19 0)
			(effects
				(font
					(size 1.27 1.27)
				)
				(hide yes)
			)
		)
		(property "Author" "Antmicro"
			(at 101.6 130.81 0)
			(effects
				(font
					(size 1.27 1.27)
					(thickness 0.15)
				)
				(justify left bottom)
				(hide yes)
			)
		)
		(property "License" "Apache-2.0"
			(at 101.6 133.35 0)
			(effects
				(font
					(size 1.27 1.27)
					(thickness 0.15)
				)
				(justify left bottom)
				(hide yes)
			)
		)
		(pin "1"
		)
		(instances
			(project "jetson-agx-thor-baseboard"
				(path ""
					(reference "#PWR073")
					(unit 1)
				)
			)
		)
	)
	(symbol
		(lib_id "antmicropower:GND")
		(at 306.07 59.69 0)
		(unit 1)
		(exclude_from_sim no)
		(in_bom yes)
		(on_board yes)
		(dnp no)
		(fields_autoplaced yes)
		(property "Reference" "#PWR0424"
			(at 306.07 66.04 0)
			(effects
				(font
					(size 1.27 1.27)
				)
				(justify left bottom)
				(hide yes)
			)
		)
		(property "Value" "GND"
			(at 306.07 63.5 0)
			(effects
				(font
					(size 1.27 1.27)
					(thickness 0.15)
				)
			)
		)
		(property "Footprint" ""
			(at 314.96 67.31 0)
			(effects
				(font
					(size 1.27 1.27)
					(thickness 0.15)
				)
				(justify left bottom)
				(hide yes)
			)
		)
		(property "Datasheet" ""
			(at 314.96 72.39 0)
			(effects
				(font
					(size 1.27 1.27)
					(thickness 0.15)
				)
				(justify left bottom)
				(hide yes)
			)
		)
		(property "Description" ""
			(at 306.07 59.69 0)
			(effects
				(font
					(size 1.27 1.27)
				)
				(hide yes)
			)
		)
		(property "Author" "Antmicro"
			(at 314.96 67.31 0)
			(effects
				(font
					(size 1.27 1.27)
					(thickness 0.15)
				)
				(justify left bottom)
				(hide yes)
			)
		)
		(property "License" "Apache-2.0"
			(at 314.96 69.85 0)
			(effects
				(font
					(size 1.27 1.27)
					(thickness 0.15)
				)
				(justify left bottom)
				(hide yes)
			)
		)
		(pin "1"
		)
		(instances
			(project "jetson-agx-thor-baseboard"
				(path ""
					(reference "#PWR0424")
					(unit 1)
				)
			)
		)
	)
	(symbol
		(lib_id "antmicroResistors0402:R_0R_0402")
		(at 342.9 137.16 0)
		(unit 1)
		(exclude_from_sim no)
		(in_bom yes)
		(on_board yes)
		(dnp no)
		(property "Reference" "R402"
			(at 340.868 136.144 0)
			(effects
				(font
					(size 1.27 1.27)
					(thickness 0.15)
				)
			)
		)
		(property "Value" "R_0R_0402"
			(at 363.22 149.86 0)
			(effects
				(font
					(size 1.27 1.27)
					(thickness 0.15)
				)
				(justify left bottom)
				(hide yes)
			)
		)
		(property "Footprint" "antmicro-footprints:R_0402_1005Metric"
			(at 363.22 152.4 0)
			(effects
				(font
					(size 1.27 1.27)
					(thickness 0.15)
				)
				(justify left bottom)
				(hide yes)
			)
		)
		(property "Datasheet" "https://industrial.panasonic.com/cdbs/www-data/pdf/RDA0000/AOA0000C301.pdf"
			(at 363.22 154.94 0)
			(effects
				(font
					(size 1.27 1.27)
					(thickness 0.15)
				)
				(justify left bottom)
				(hide yes)
			)
		)
		(property "Description" "SMD Chip Resistor, Jumper, 0 ohm, 100 mW, 0402 [1005 Metric], Thick Film, General Purpose"
			(at 363.22 170.18 0)
			(effects
				(font
					(size 1.27 1.27)
				)
				(justify left bottom)
				(hide yes)
			)
		)
		(property "MPN" "ERJ2GE0R00X"
			(at 363.22 157.48 0)
			(effects
				(font
					(size 1.27 1.27)
					(thickness 0.15)
				)
				(justify left bottom)
				(hide yes)
			)
		)
		(property "Manufacturer" "Panasonic"
			(at 363.22 160.02 0)
			(effects
				(font
					(size 1.27 1.27)
					(thickness 0.15)
				)
				(justify left bottom)
				(hide yes)
			)
		)
		(property "License" "Apache-2.0"
			(at 363.22 162.56 0)
			(effects
				(font
					(size 1.27 1.27)
					(thickness 0.15)
				)
				(justify left bottom)
				(hide yes)
			)
		)
		(property "Author" "Antmicro"
			(at 363.22 165.1 0)
			(effects
				(font
					(size 1.27 1.27)
					(thickness 0.15)
				)
				(justify left bottom)
				(hide yes)
			)
		)
		(property "Val" "0R"
			(at 348.742 136.144 0)
			(effects
				(font
					(size 1.27 1.27)
					(thickness 0.15)
				)
			)
		)
		(property "Tolerance" "~"
			(at 363.22 147.32 0)
			(effects
				(font
					(size 1.27 1.27)
				)
				(justify left bottom)
				(hide yes)
			)
		)
		(property "Current" "1A"
			(at 363.22 167.64 0)
			(effects
				(font
					(size 1.27 1.27)
					(thickness 0.15)
				)
				(justify left bottom)
				(hide yes)
			)
		)
		(pin "2"
		)
		(pin "1"
		)
		(instances
			(project "jetson-agx-thor-baseboard"
				(path ""
					(reference "R402")
					(unit 1)
				)
			)
		)
	)
	(symbol
		(lib_id "antmicroWire2BoardConnectors:JST_SH_1x4_SM04B-SRSS-TB-LF-SN")
		(at 241.3 74.93 0)
		(unit 1)
		(exclude_from_sim no)
		(in_bom yes)
		(on_board yes)
		(dnp no)
		(property "Reference" "J16"
			(at 245.11 71.12 0)
			(effects
				(font
					(size 1.27 1.27)
					(thickness 0.15)
				)
			)
		)
		(property "Value" "JST_SH_1x4_SM04B-SRSS-TB-LF-SN"
			(at 267.97 82.55 0)
			(effects
				(font
					(size 1.27 1.27)
					(thickness 0.15)
				)
				(justify left bottom)
				(hide yes)
			)
		)
		(property "Footprint" "antmicro-footprints:Conn_JST_SH_1x4_SM04B-SRSS-TB-LF-SN"
			(at 267.97 85.09 0)
			(effects
				(font
					(size 1.27 1.27)
					(thickness 0.15)
				)
				(justify left bottom)
				(hide yes)
			)
		)
		(property "Datasheet" "https://www.jst-mfg.com/product/pdf/eng/eSH.pdf"
			(at 267.97 87.63 0)
			(effects
				(font
					(size 1.27 1.27)
					(thickness 0.15)
				)
				(justify left bottom)
				(hide yes)
			)
		)
		(property "Description" "Pin Header, Right Angle, Wire-to-Board, 1 mm, 1 Rows, 4 Contacts, Surface Mount Right Angle, SH"
			(at 241.3 74.93 0)
			(effects
				(font
					(size 1.27 1.27)
				)
				(hide yes)
			)
		)
		(property "MPN" "SM04B-SRSS-TB(LF)(SN)"
			(at 248.285 80.01 90)
			(effects
				(font
					(size 1.27 1.27)
					(thickness 0.15)
				)
			)
		)
		(property "Manufacturer" "JST Automotive Connectors"
			(at 267.97 90.17 0)
			(effects
				(font
					(size 1.27 1.27)
					(thickness 0.15)
				)
				(justify left bottom)
				(hide yes)
			)
		)
		(property "Author" "Antmicro"
			(at 267.97 92.71 0)
			(effects
				(font
					(size 1.27 1.27)
					(thickness 0.15)
				)
				(justify left bottom)
				(hide yes)
			)
		)
		(property "License" "Apache-2.0"
			(at 267.97 95.25 0)
			(effects
				(font
					(size 1.27 1.27)
					(thickness 0.15)
				)
				(justify left bottom)
				(hide yes)
			)
		)
		(pin "1"
		)
		(pin "2"
		)
		(pin "3"
		)
		(pin "4"
		)
		(pin "MP"
		)
		(instances
			(project "jetson-agx-thor-baseboard"
				(path ""
					(reference "J16")
					(unit 1)
				)
			)
		)
	)
	(symbol
		(lib_id "antmicropower:GND")
		(at 68.58 151.13 0)
		(unit 1)
		(exclude_from_sim no)
		(in_bom yes)
		(on_board yes)
		(dnp no)
		(fields_autoplaced yes)
		(property "Reference" "#PWR0390"
			(at 68.58 157.48 0)
			(effects
				(font
					(size 1.27 1.27)
				)
				(justify left bottom)
				(hide yes)
			)
		)
		(property "Value" "GND"
			(at 68.58 154.94 0)
			(effects
				(font
					(size 1.27 1.27)
					(thickness 0.15)
				)
			)
		)
		(property "Footprint" ""
			(at 77.47 158.75 0)
			(effects
				(font
					(size 1.27 1.27)
					(thickness 0.15)
				)
				(justify left bottom)
				(hide yes)
			)
		)
		(property "Datasheet" ""
			(at 77.47 163.83 0)
			(effects
				(font
					(size 1.27 1.27)
					(thickness 0.15)
				)
				(justify left bottom)
				(hide yes)
			)
		)
		(property "Description" ""
			(at 68.58 151.13 0)
			(effects
				(font
					(size 1.27 1.27)
				)
				(hide yes)
			)
		)
		(property "Author" "Antmicro"
			(at 77.47 158.75 0)
			(effects
				(font
					(size 1.27 1.27)
					(thickness 0.15)
				)
				(justify left bottom)
				(hide yes)
			)
		)
		(property "License" "Apache-2.0"
			(at 77.47 161.29 0)
			(effects
				(font
					(size 1.27 1.27)
					(thickness 0.15)
				)
				(justify left bottom)
				(hide yes)
			)
		)
		(pin "1"
		)
		(instances
			(project "jetson-agx-thor-baseboard"
				(path ""
					(reference "#PWR0390")
					(unit 1)
				)
			)
		)
	)
	(symbol
		(lib_id "antmicroResistors0402:R_200R_0402")
		(at 316.23 58.42 270)
		(mirror x)
		(unit 1)
		(exclude_from_sim no)
		(in_bom yes)
		(on_board yes)
		(dnp no)
		(property "Reference" "R246"
			(at 317.5 54.61 90)
			(effects
				(font
					(size 1.27 1.27)
				)
				(justify left)
			)
		)
		(property "Value" "R_200R_0402"
			(at 303.53 38.1 0)
			(effects
				(font
					(size 1.27 1.27)
					(thickness 0.15)
				)
				(justify left bottom)
				(hide yes)
			)
		)
		(property "Footprint" "antmicro-footprints:R_0402_1005Metric"
			(at 300.99 38.1 0)
			(effects
				(font
					(size 1.27 1.27)
					(thickness 0.15)
				)
				(justify left bottom)
				(hide yes)
			)
		)
		(property "Datasheet" "https://www.bourns.com/docs/product-datasheets/cr.pdf"
			(at 298.45 38.1 0)
			(effects
				(font
					(size 1.27 1.27)
					(thickness 0.15)
				)
				(justify left bottom)
				(hide yes)
			)
		)
		(property "Description" "SMD Chip Resistor, 200 ohm, ± 1%, 62.5 mW, 0402 [1005 Metric], Thick Film, General Purpose"
			(at 316.23 58.42 0)
			(effects
				(font
					(size 1.27 1.27)
				)
				(hide yes)
			)
		)
		(property "Manufacturer" "Bourns"
			(at 293.37 38.1 0)
			(effects
				(font
					(size 1.27 1.27)
					(thickness 0.15)
				)
				(justify left bottom)
				(hide yes)
			)
		)
		(property "MPN" "CR0402-FX-2000GLF"
			(at 295.91 38.1 0)
			(effects
				(font
					(size 1.27 1.27)
					(thickness 0.15)
				)
				(justify left bottom)
				(hide yes)
			)
		)
		(property "Val" "200R"
			(at 317.5 57.15 90)
			(effects
				(font
					(size 1.27 1.27)
					(thickness 0.15)
				)
				(justify left)
			)
		)
		(property "License" "Apache-2.0"
			(at 290.83 38.1 0)
			(effects
				(font
					(size 1.27 1.27)
					(thickness 0.15)
				)
				(justify left bottom)
				(hide yes)
			)
		)
		(property "Author" "Antmicro"
			(at 288.29 38.1 0)
			(effects
				(font
					(size 1.27 1.27)
					(thickness 0.15)
				)
				(justify left bottom)
				(hide yes)
			)
		)
		(property "Tolerance" "1%"
			(at 306.07 38.1 0)
			(effects
				(font
					(size 1.27 1.27)
				)
				(justify left bottom)
				(hide yes)
			)
		)
		(pin "1"
		)
		(pin "2"
		)
		(instances
			(project "jetson-agx-thor-baseboard"
				(path ""
					(reference "R246")
					(unit 1)
				)
			)
		)
	)
	(symbol
		(lib_id "antmicropower:GND")
		(at 300.99 157.48 0)
		(unit 1)
		(exclude_from_sim no)
		(in_bom yes)
		(on_board yes)
		(dnp no)
		(fields_autoplaced yes)
		(property "Reference" "#PWR0644"
			(at 300.99 163.83 0)
			(effects
				(font
					(size 1.27 1.27)
				)
				(justify left bottom)
				(hide yes)
			)
		)
		(property "Value" "GND"
			(at 300.99 161.29 0)
			(effects
				(font
					(size 1.27 1.27)
					(thickness 0.15)
				)
			)
		)
		(property "Footprint" ""
			(at 309.88 165.1 0)
			(effects
				(font
					(size 1.27 1.27)
					(thickness 0.15)
				)
				(justify left bottom)
				(hide yes)
			)
		)
		(property "Datasheet" ""
			(at 309.88 170.18 0)
			(effects
				(font
					(size 1.27 1.27)
					(thickness 0.15)
				)
				(justify left bottom)
				(hide yes)
			)
		)
		(property "Description" ""
			(at 300.99 157.48 0)
			(effects
				(font
					(size 1.27 1.27)
				)
				(hide yes)
			)
		)
		(property "Author" "Antmicro"
			(at 309.88 165.1 0)
			(effects
				(font
					(size 1.27 1.27)
					(thickness 0.15)
				)
				(justify left bottom)
				(hide yes)
			)
		)
		(property "License" "Apache-2.0"
			(at 309.88 167.64 0)
			(effects
				(font
					(size 1.27 1.27)
					(thickness 0.15)
				)
				(justify left bottom)
				(hide yes)
			)
		)
		(pin "1"
		)
		(instances
			(project "jetson-agx-thor-baseboard"
				(path ""
					(reference "#PWR0644")
					(unit 1)
				)
			)
		)
	)
	(symbol
		(lib_id "antmicropower:GND")
		(at 210.82 251.46 0)
		(unit 1)
		(exclude_from_sim no)
		(in_bom yes)
		(on_board yes)
		(dnp no)
		(fields_autoplaced yes)
		(property "Reference" "#PWR0408"
			(at 210.82 257.81 0)
			(effects
				(font
					(size 1.27 1.27)
				)
				(justify left bottom)
				(hide yes)
			)
		)
		(property "Value" "GND"
			(at 210.82 255.27 0)
			(effects
				(font
					(size 1.27 1.27)
					(thickness 0.15)
				)
			)
		)
		(property "Footprint" ""
			(at 219.71 259.08 0)
			(effects
				(font
					(size 1.27 1.27)
					(thickness 0.15)
				)
				(justify left bottom)
				(hide yes)
			)
		)
		(property "Datasheet" ""
			(at 219.71 264.16 0)
			(effects
				(font
					(size 1.27 1.27)
					(thickness 0.15)
				)
				(justify left bottom)
				(hide yes)
			)
		)
		(property "Description" ""
			(at 210.82 251.46 0)
			(effects
				(font
					(size 1.27 1.27)
				)
				(hide yes)
			)
		)
		(property "Author" "Antmicro"
			(at 219.71 259.08 0)
			(effects
				(font
					(size 1.27 1.27)
					(thickness 0.15)
				)
				(justify left bottom)
				(hide yes)
			)
		)
		(property "License" "Apache-2.0"
			(at 219.71 261.62 0)
			(effects
				(font
					(size 1.27 1.27)
					(thickness 0.15)
				)
				(justify left bottom)
				(hide yes)
			)
		)
		(pin "1"
		)
		(instances
			(project "jetson-agx-thor-baseboard"
				(path ""
					(reference "#PWR0408")
					(unit 1)
				)
			)
		)
	)
	(symbol
		(lib_id "antmicroTestPoints:TP_0.75mm_SMD")
		(at 30.48 140.97 90)
		(unit 1)
		(exclude_from_sim no)
		(in_bom no)
		(on_board yes)
		(dnp no)
		(property "Reference" "TP89"
			(at 33.02 135.89 90)
			(effects
				(font
					(size 1.27 1.27)
					(thickness 0.15)
				)
				(justify left)
			)
		)
		(property "Value" "TP_0.75mm_SMD"
			(at 34.29 130.81 0)
			(effects
				(font
					(size 1.27 1.27)
					(thickness 0.15)
				)
				(justify left bottom)
				(hide yes)
			)
		)
		(property "Footprint" "antmicro-footprints:TP_SMD_0.75mm"
			(at 36.83 130.81 0)
			(effects
				(font
					(size 1.27 1.27)
					(thickness 0.15)
				)
				(justify left bottom)
				(hide yes)
			)
		)
		(property "Datasheet" ""
			(at 43.18 123.19 0)
			(effects
				(font
					(size 1.27 1.27)
					(thickness 0.15)
				)
				(justify left bottom)
				(hide yes)
			)
		)
		(property "Description" "SMT test point"
			(at 30.48 140.97 0)
			(effects
				(font
					(size 1.27 1.27)
				)
				(hide yes)
			)
		)
		(property "MPN" ""
			(at 41.91 130.175 0)
			(effects
				(font
					(size 1.27 1.27)
					(thickness 0.15)
				)
				(justify left bottom)
				(hide yes)
			)
		)
		(property "Manufacturer" ""
			(at 36.83 130.175 0)
			(effects
				(font
					(size 1.27 1.27)
					(thickness 0.15)
				)
				(justify left bottom)
				(hide yes)
			)
		)
		(property "Author" "Antmicro"
			(at 39.37 130.81 0)
			(effects
				(font
					(size 1.27 1.27)
					(thickness 0.15)
				)
				(justify left bottom)
				(hide yes)
			)
		)
		(property "License" "Apache-2.0"
			(at 41.91 130.81 0)
			(effects
				(font
					(size 1.27 1.27)
					(thickness 0.15)
				)
				(justify left bottom)
				(hide yes)
			)
		)
		(pin "1"
		)
		(instances
			(project "jetson-agx-thor-baseboard"
				(path ""
					(reference "TP89")
					(unit 1)
				)
			)
		)
	)
	(symbol
		(lib_id "antmicropower:GND")
		(at 196.85 154.94 0)
		(unit 1)
		(exclude_from_sim no)
		(in_bom yes)
		(on_board yes)
		(dnp no)
		(fields_autoplaced yes)
		(property "Reference" "#PWR0628"
			(at 205.74 157.48 0)
			(effects
				(font
					(size 1.27 1.27)
					(thickness 0.15)
				)
				(justify left bottom)
				(hide yes)
			)
		)
		(property "Value" "GND"
			(at 196.85 160.02 0)
			(effects
				(font
					(size 1.27 1.27)
					(thickness 0.15)
				)
			)
		)
		(property "Footprint" ""
			(at 205.74 162.56 0)
			(effects
				(font
					(size 1.27 1.27)
					(thickness 0.15)
				)
				(justify left bottom)
				(hide yes)
			)
		)
		(property "Datasheet" ""
			(at 205.74 167.64 0)
			(effects
				(font
					(size 1.27 1.27)
					(thickness 0.15)
				)
				(justify left bottom)
				(hide yes)
			)
		)
		(property "Description" ""
			(at 205.74 170.18 0)
			(effects
				(font
					(size 1.27 1.27)
				)
				(justify left bottom)
				(hide yes)
			)
		)
		(property "Author" "Antmicro"
			(at 205.74 162.56 0)
			(effects
				(font
					(size 1.27 1.27)
					(thickness 0.15)
				)
				(justify left bottom)
				(hide yes)
			)
		)
		(property "License" "Apache-2.0"
			(at 205.74 165.1 0)
			(effects
				(font
					(size 1.27 1.27)
					(thickness 0.15)
				)
				(justify left bottom)
				(hide yes)
			)
		)
		(pin "1"
		)
		(instances
			(project ""
				(path ""
					(reference "#PWR0628")
					(unit 1)
				)
			)
		)
	)
	(symbol
		(lib_id "antmicroResistors0402:R_100k_0402")
		(at 279.4 60.96 90)
		(unit 1)
		(exclude_from_sim no)
		(in_bom no)
		(on_board yes)
		(dnp yes)
		(property "Reference" "R244"
			(at 280.67 57.15 90)
			(effects
				(font
					(size 1.27 1.27)
				)
				(justify right)
			)
		)
		(property "Value" "R_100k_0402"
			(at 292.1 40.64 0)
			(effects
				(font
					(size 1.27 1.27)
					(thickness 0.15)
				)
				(justify left bottom)
				(hide yes)
			)
		)
		(property "Footprint" "antmicro-footprints:R_0402_1005Metric"
			(at 294.64 40.64 0)
			(effects
				(font
					(size 1.27 1.27)
					(thickness 0.15)
				)
				(justify left bottom)
				(hide yes)
			)
		)
		(property "Datasheet" "https://www.bourns.com/docs/product-datasheets/cr.pdf"
			(at 297.18 40.64 0)
			(effects
				(font
					(size 1.27 1.27)
					(thickness 0.15)
				)
				(justify left bottom)
				(hide yes)
			)
		)
		(property "Description" "SMD Chip Resistor, 100 kohm, ± 1%, 62.5 mW, 0402 [1005 Metric], Thick Film, General Purpose"
			(at 279.4 60.96 0)
			(effects
				(font
					(size 1.27 1.27)
				)
				(hide yes)
			)
		)
		(property "Manufacturer" "Bourns"
			(at 302.26 40.64 0)
			(effects
				(font
					(size 1.27 1.27)
					(thickness 0.15)
				)
				(justify left bottom)
				(hide yes)
			)
		)
		(property "MPN" "CR0402-FX-1003GLF"
			(at 299.72 40.64 0)
			(effects
				(font
					(size 1.27 1.27)
					(thickness 0.15)
				)
				(justify left bottom)
				(hide yes)
			)
		)
		(property "Val" "100k"
			(at 280.67 59.69 90)
			(effects
				(font
					(size 1.27 1.27)
					(thickness 0.15)
				)
				(justify right)
			)
		)
		(property "License" "Apache-2.0"
			(at 304.8 40.64 0)
			(effects
				(font
					(size 1.27 1.27)
					(thickness 0.15)
				)
				(justify left bottom)
				(hide yes)
			)
		)
		(property "Author" "Antmicro"
			(at 307.34 40.64 0)
			(effects
				(font
					(size 1.27 1.27)
					(thickness 0.15)
				)
				(justify left bottom)
				(hide yes)
			)
		)
		(property "Tolerance" "1%"
			(at 289.56 40.64 0)
			(effects
				(font
					(size 1.27 1.27)
				)
				(justify left bottom)
				(hide yes)
			)
		)
		(pin "1"
		)
		(pin "2"
		)
		(instances
			(project "jetson-agx-thor-baseboard"
				(path ""
					(reference "R244")
					(unit 1)
				)
			)
		)
	)
	(symbol
		(lib_id "antmicroPushbuttonSwitches:SW_KMR211NGLFS_SMD")
		(at 210.82 238.76 270)
		(unit 1)
		(exclude_from_sim no)
		(in_bom yes)
		(on_board yes)
		(dnp no)
		(property "Reference" "S3"
			(at 214.63 242.57 90)
			(effects
				(font
					(size 1.27 1.27)
				)
				(justify left)
			)
		)
		(property "Value" "SW_KMR211NGLFS_SMD"
			(at 203.2 264.16 0)
			(effects
				(font
					(size 1.27 1.27)
					(thickness 0.15)
				)
				(justify left bottom)
				(hide yes)
			)
		)
		(property "Footprint" "antmicro-footprints:SW_KMR211NGLFS_SMD"
			(at 200.66 264.16 0)
			(effects
				(font
					(size 1.27 1.27)
					(thickness 0.15)
				)
				(justify left bottom)
				(hide yes)
			)
		)
		(property "Datasheet" "http://www.farnell.com/datasheets/2631211.pdf"
			(at 198.12 264.16 0)
			(effects
				(font
					(size 1.27 1.27)
					(thickness 0.15)
				)
				(justify left bottom)
				(hide yes)
			)
		)
		(property "Description" "Tactile Switch, KMR 2 Series, Top Actuated, Surface Mount, Oval Button, 120 gf, 50mA at 32VDC"
			(at 210.82 238.76 0)
			(effects
				(font
					(size 1.27 1.27)
				)
				(hide yes)
			)
		)
		(property "MPN" "KMR211NGLFS"
			(at 214.63 245.11 90)
			(effects
				(font
					(size 1.27 1.27)
					(thickness 0.15)
				)
				(justify left)
			)
		)
		(property "Manufacturer" "C&K"
			(at 195.58 264.16 0)
			(effects
				(font
					(size 1.27 1.27)
					(thickness 0.15)
				)
				(justify left bottom)
				(hide yes)
			)
		)
		(property "Author" "Antmicro"
			(at 193.04 264.16 0)
			(effects
				(font
					(size 1.27 1.27)
					(thickness 0.15)
				)
				(justify left bottom)
				(hide yes)
			)
		)
		(property "License" "Apache-2.0"
			(at 190.5 264.16 0)
			(effects
				(font
					(size 1.27 1.27)
					(thickness 0.15)
				)
				(justify left bottom)
				(hide yes)
			)
		)
		(pin "1"
		)
		(pin "2"
		)
		(pin "3"
		)
		(pin "4"
		)
		(instances
			(project "jetson-agx-thor-baseboard"
				(path ""
					(reference "S3")
					(unit 1)
				)
			)
		)
	)
	(symbol
		(lib_id "antmicroResistors0402:R_0R_0402")
		(at 342.9 147.32 0)
		(unit 1)
		(exclude_from_sim no)
		(in_bom yes)
		(on_board yes)
		(dnp no)
		(property "Reference" "R406"
			(at 340.868 146.304 0)
			(effects
				(font
					(size 1.27 1.27)
					(thickness 0.15)
				)
			)
		)
		(property "Value" "R_0R_0402"
			(at 363.22 160.02 0)
			(effects
				(font
					(size 1.27 1.27)
					(thickness 0.15)
				)
				(justify left bottom)
				(hide yes)
			)
		)
		(property "Footprint" "antmicro-footprints:R_0402_1005Metric"
			(at 363.22 162.56 0)
			(effects
				(font
					(size 1.27 1.27)
					(thickness 0.15)
				)
				(justify left bottom)
				(hide yes)
			)
		)
		(property "Datasheet" "https://industrial.panasonic.com/cdbs/www-data/pdf/RDA0000/AOA0000C301.pdf"
			(at 363.22 165.1 0)
			(effects
				(font
					(size 1.27 1.27)
					(thickness 0.15)
				)
				(justify left bottom)
				(hide yes)
			)
		)
		(property "Description" "SMD Chip Resistor, Jumper, 0 ohm, 100 mW, 0402 [1005 Metric], Thick Film, General Purpose"
			(at 363.22 180.34 0)
			(effects
				(font
					(size 1.27 1.27)
				)
				(justify left bottom)
				(hide yes)
			)
		)
		(property "MPN" "ERJ2GE0R00X"
			(at 363.22 167.64 0)
			(effects
				(font
					(size 1.27 1.27)
					(thickness 0.15)
				)
				(justify left bottom)
				(hide yes)
			)
		)
		(property "Manufacturer" "Panasonic"
			(at 363.22 170.18 0)
			(effects
				(font
					(size 1.27 1.27)
					(thickness 0.15)
				)
				(justify left bottom)
				(hide yes)
			)
		)
		(property "License" "Apache-2.0"
			(at 363.22 172.72 0)
			(effects
				(font
					(size 1.27 1.27)
					(thickness 0.15)
				)
				(justify left bottom)
				(hide yes)
			)
		)
		(property "Author" "Antmicro"
			(at 363.22 175.26 0)
			(effects
				(font
					(size 1.27 1.27)
					(thickness 0.15)
				)
				(justify left bottom)
				(hide yes)
			)
		)
		(property "Val" "0R"
			(at 348.742 146.304 0)
			(effects
				(font
					(size 1.27 1.27)
					(thickness 0.15)
				)
			)
		)
		(property "Tolerance" "~"
			(at 363.22 157.48 0)
			(effects
				(font
					(size 1.27 1.27)
				)
				(justify left bottom)
				(hide yes)
			)
		)
		(property "Current" "1A"
			(at 363.22 177.8 0)
			(effects
				(font
					(size 1.27 1.27)
					(thickness 0.15)
				)
				(justify left bottom)
				(hide yes)
			)
		)
		(pin "2"
		)
		(pin "1"
		)
		(instances
			(project "jetson-agx-thor-baseboard"
				(path ""
					(reference "R406")
					(unit 1)
				)
			)
		)
	)
	(symbol
		(lib_id "antmicropower:GND")
		(at 86.36 92.71 0)
		(unit 1)
		(exclude_from_sim no)
		(in_bom yes)
		(on_board yes)
		(dnp no)
		(fields_autoplaced yes)
		(property "Reference" "#PWR0397"
			(at 86.36 99.06 0)
			(effects
				(font
					(size 1.27 1.27)
				)
				(justify left bottom)
				(hide yes)
			)
		)
		(property "Value" "GND"
			(at 86.36 96.52 0)
			(effects
				(font
					(size 1.27 1.27)
					(thickness 0.15)
				)
			)
		)
		(property "Footprint" ""
			(at 95.25 100.33 0)
			(effects
				(font
					(size 1.27 1.27)
					(thickness 0.15)
				)
				(justify left bottom)
				(hide yes)
			)
		)
		(property "Datasheet" ""
			(at 95.25 105.41 0)
			(effects
				(font
					(size 1.27 1.27)
					(thickness 0.15)
				)
				(justify left bottom)
				(hide yes)
			)
		)
		(property "Description" ""
			(at 86.36 92.71 0)
			(effects
				(font
					(size 1.27 1.27)
				)
				(hide yes)
			)
		)
		(property "Author" "Antmicro"
			(at 95.25 100.33 0)
			(effects
				(font
					(size 1.27 1.27)
					(thickness 0.15)
				)
				(justify left bottom)
				(hide yes)
			)
		)
		(property "License" "Apache-2.0"
			(at 95.25 102.87 0)
			(effects
				(font
					(size 1.27 1.27)
					(thickness 0.15)
				)
				(justify left bottom)
				(hide yes)
			)
		)
		(pin "1"
		)
		(instances
			(project "jetson-agx-thor-baseboard"
				(path ""
					(reference "#PWR0397")
					(unit 1)
				)
			)
		)
	)
)
